G04 ================== begin FILE IDENTIFICATION RECORD ==================*
G04 Layout Name:  D:/<user>/Wistron_project/16315-1/gbr/16315-1.brd*
G04 Film Name:    L7VCC*
G04 File Format:  Gerber RS274X*
G04 File Origin:  Cadence Allegro 16.5-S056*
G04 Origin Date:  Fri Jun 09 15:31:47 2017*
G04 *
G04 Layer:  VIA CLASS/L7VCC*
G04 Layer:  PIN/L7VCC*
G04 Layer:  PACKAGE GEOMETRY/PWRVCC*
G04 Layer:  ETCH/L7VCC*
G04 Layer:  DRAWING FORMAT/LAYER_PCB_STORY*
G04 Layer:  DRAWING FORMAT/LAYER_L7VCC*
G04 *
G04 Offset:    (0.00 0.00)*
G04 Mirror:    No*
G04 Mode:      Negative*
G04 Rotation:  0*
G04 FullContactRelief:  No*
G04 UndefLineWidth:     6.00*
G04 ================== end FILE IDENTIFICATION RECORD ====================*
%FSLAX35Y35*MOIN*%
%IR0*IPPOS*OFA0.00000B0.00000*MIA0B0*SFA1.00000B1.00000*%
%ADD23C,.03*%
%ADD43C,.04*%
%ADD14C,.032*%
%ADD45C,.034*%
%ADD42C,.052*%
%ADD31C,.043*%
%ADD22C,.036*%
%ADD20C,.081*%
%ADD19C,.065*%
%ADD37C,.057*%
%ADD41C,.058*%
%AMMACRO29*
4,1,15,.00398,.00044,
.003999,.000208,
.004004,-.000025,
.003996,-.000258,
.00398,-.00044,
.00483,-.00129,
.004897,-.001007,
.004947,-.000721,
.004981,-.000432,
.004997,-.000141,
.004997,.000149,
.00498,.00044,
.004946,.000729,
.004895,.001015,
.00483,.00129,
.00398,.00044,
90.*
4,1,15,.00044,-.00398,
.000208,-.003999,
-.000025,-.004004,
-.000258,-.003996,
-.00044,-.00398,
-.00129,-.00483,
-.001007,-.004897,
-.000721,-.004947,
-.000432,-.004981,
-.000141,-.004997,
.000149,-.004997,
.00044,-.00498,
.000729,-.004946,
.001015,-.004895,
.00129,-.00483,
.00044,-.00398,
90.*
4,1,15,-.00398,-.00044,
-.003999,-.000208,
-.004004,.000025,
-.003996,.000258,
-.00398,.00044,
-.00483,.00129,
-.004897,.001007,
-.004947,.000721,
-.004981,.000432,
-.004997,.000141,
-.004997,-.000149,
-.00498,-.00044,
-.004946,-.000729,
-.004895,-.001015,
-.00483,-.00129,
-.00398,-.00044,
90.*
4,1,15,-.00044,.00398,
-.000208,.003999,
.000025,.004004,
.000258,.003996,
.00044,.00398,
.00129,.00483,
.001007,.004897,
.000721,.004947,
.000432,.004981,
.000141,.004997,
-.000149,.004997,
-.00044,.00498,
-.000729,.004946,
-.001015,.004895,
-.00129,.00483,
-.00044,.00398,
90.*
%
%ADD29MACRO29*%
%AMMACRO35*
4,1,15,-.00398,.00044,
-.003999,.000208,
-.004004,-.000025,
-.003996,-.000258,
-.00398,-.00044,
-.00483,-.00129,
-.004897,-.001007,
-.004947,-.000721,
-.004981,-.000432,
-.004997,-.000141,
-.004997,.000149,
-.00498,.00044,
-.004946,.000729,
-.004895,.001015,
-.00483,.00129,
-.00398,.00044,
90.*
4,1,15,-.00044,-.00398,
-.000208,-.003999,
.000025,-.004004,
.000258,-.003996,
.00044,-.00398,
.00129,-.00483,
.001007,-.004897,
.000721,-.004947,
.000432,-.004981,
.000141,-.004997,
-.000149,-.004997,
-.00044,-.00498,
-.000729,-.004946,
-.001015,-.004895,
-.00129,-.00483,
-.00044,-.00398,
90.*
4,1,15,.00398,-.00044,
.003999,-.000208,
.004004,.000025,
.003996,.000258,
.00398,.00044,
.00483,.00129,
.004897,.001007,
.004947,.000721,
.004981,.000432,
.004997,.000141,
.004997,-.000149,
.00498,-.00044,
.004946,-.000729,
.004895,-.001015,
.00483,-.00129,
.00398,-.00044,
90.*
4,1,15,.00044,.00398,
.000208,.003999,
-.000025,.004004,
-.000258,.003996,
-.00044,.00398,
-.00129,.00483,
-.001007,.004897,
-.000721,.004947,
-.000432,.004981,
-.000141,.004997,
.000149,.004997,
.00044,.00498,
.000729,.004946,
.001015,.004895,
.00129,.00483,
.00044,.00398,
90.*
%
%ADD35MACRO35*%
%AMMACRO11*
4,1,15,.00398,.00044,
.003999,.000208,
.004004,-.000025,
.003996,-.000258,
.00398,-.00044,
.00483,-.00129,
.004897,-.001007,
.004947,-.000721,
.004981,-.000432,
.004997,-.000141,
.004997,.000149,
.00498,.00044,
.004946,.000729,
.004895,.001015,
.00483,.00129,
.00398,.00044,
0.0*
4,1,15,.00044,-.00398,
.000208,-.003999,
-.000025,-.004004,
-.000258,-.003996,
-.00044,-.00398,
-.00129,-.00483,
-.001007,-.004897,
-.000721,-.004947,
-.000432,-.004981,
-.000141,-.004997,
.000149,-.004997,
.00044,-.00498,
.000729,-.004946,
.001015,-.004895,
.00129,-.00483,
.00044,-.00398,
0.0*
4,1,15,-.00398,-.00044,
-.003999,-.000208,
-.004004,.000025,
-.003996,.000258,
-.00398,.00044,
-.00483,.00129,
-.004897,.001007,
-.004947,.000721,
-.004981,.000432,
-.004997,.000141,
-.004997,-.000149,
-.00498,-.00044,
-.004946,-.000729,
-.004895,-.001015,
-.00483,-.00129,
-.00398,-.00044,
0.0*
4,1,15,-.00044,.00398,
-.000208,.003999,
.000025,.004004,
.000258,.003996,
.00044,.00398,
.00129,.00483,
.001007,.004897,
.000721,.004947,
.000432,.004981,
.000141,.004997,
-.000149,.004997,
-.00044,.00498,
-.000729,.004946,
-.001015,.004895,
-.00129,.00483,
-.00044,.00398,
0.0*
%
%ADD11MACRO11*%
%AMMACRO36*
4,1,47,.19499,.0719,
.215281,.036007,
.229031,-.002865,
.235822,-.043533,
.235448,-.084763,
.22792,-.125302,
.213467,-.163917,
.192528,-.199436,
.16574,-.23078,
.133915,-.256995,
.098022,-.277286,
.059151,-.291036,
.018482,-.297827,
-.022748,-.297453,
-.063286,-.289925,
-.101902,-.275472,
-.137421,-.254533,
-.168764,-.227745,
-.19498,-.19592,
-.215271,-.160027,
-.229021,-.121156,
-.235812,-.080487,
-.235438,-.039257,
-.22791,.001281,
-.213457,.039897,
-.19498,.0719,
-.17079,.109417,
-.148822,.148276,
-.129151,.188348,
-.11538,.22052,
-.105587,.239854,
-.092586,.257193,
-.076771,.272012,
-.058623,.283859,
-.038693,.292375,
-.017588,.297301,
.004052,.298487,
.025569,.295897,
.04631,.28961,
.065644,.279817,
.082983,.266816,
.097802,.251001,
.109649,.232853,
.1154,.22052,
.133222,.179593,
.153393,.139771,
.175846,.101189,
.19499,.0719,
0.0*
%
%ADD36MACRO36*%
%AMMACRO24*
4,1,15,-.00398,.00044,
-.003999,.000208,
-.004004,-.000025,
-.003996,-.000258,
-.00398,-.00044,
-.00483,-.00129,
-.004897,-.001007,
-.004947,-.000721,
-.004981,-.000432,
-.004997,-.000141,
-.004997,.000149,
-.00498,.00044,
-.004946,.000729,
-.004895,.001015,
-.00483,.00129,
-.00398,.00044,
0.0*
4,1,15,-.00044,-.00398,
-.000208,-.003999,
.000025,-.004004,
.000258,-.003996,
.00044,-.00398,
.00129,-.00483,
.001007,-.004897,
.000721,-.004947,
.000432,-.004981,
.000141,-.004997,
-.000149,-.004997,
-.00044,-.00498,
-.000729,-.004946,
-.001015,-.004895,
-.00129,-.00483,
-.00044,-.00398,
0.0*
4,1,15,.00398,-.00044,
.003999,-.000208,
.004004,.000025,
.003996,.000258,
.00398,.00044,
.00483,.00129,
.004897,.001007,
.004947,.000721,
.004981,.000432,
.004997,.000141,
.004997,-.000149,
.00498,-.00044,
.004946,-.000729,
.004895,-.001015,
.00483,-.00129,
.00398,-.00044,
0.0*
4,1,15,.00044,.00398,
.000208,.003999,
-.000025,.004004,
-.000258,.003996,
-.00044,.00398,
-.00129,.00483,
-.001007,.004897,
-.000721,.004947,
-.000432,.004981,
-.000141,.004997,
.000149,.004997,
.00044,.00498,
.000729,.004946,
.001015,.004895,
.00129,.00483,
.00044,.00398,
0.0*
%
%ADD24MACRO24*%
%ADD38C,.121*%
%ADD32C,.122*%
%ADD16C,.114*%
%ADD18C,.115*%
%ADD12O,.206X.285*%
%ADD33C,.125*%
%ADD10C,.206*%
%ADD34C,.432*%
%ADD25C,.18*%
%ADD13C,.208*%
%ADD39O,.159X.237*%
%ADD26C,.139*%
%ADD17C,.265*%
%ADD40C,.159*%
%ADD44C,.178*%
%AMMACRO30*
4,1,15,.00398,.00044,
.003999,.000208,
.004004,-.000025,
.003996,-.000258,
.00398,-.00044,
.00483,-.00129,
.004897,-.001007,
.004947,-.000721,
.004981,-.000432,
.004997,-.000141,
.004997,.000149,
.00498,.00044,
.004946,.000729,
.004895,.001015,
.00483,.00129,
.00398,.00044,
270.*
4,1,15,.00044,-.00398,
.000208,-.003999,
-.000025,-.004004,
-.000258,-.003996,
-.00044,-.00398,
-.00129,-.00483,
-.001007,-.004897,
-.000721,-.004947,
-.000432,-.004981,
-.000141,-.004997,
.000149,-.004997,
.00044,-.00498,
.000729,-.004946,
.001015,-.004895,
.00129,-.00483,
.00044,-.00398,
270.*
4,1,15,-.00398,-.00044,
-.003999,-.000208,
-.004004,.000025,
-.003996,.000258,
-.00398,.00044,
-.00483,.00129,
-.004897,.001007,
-.004947,.000721,
-.004981,.000432,
-.004997,.000141,
-.004997,-.000149,
-.00498,-.00044,
-.004946,-.000729,
-.004895,-.001015,
-.00483,-.00129,
-.00398,-.00044,
270.*
4,1,15,-.00044,.00398,
-.000208,.003999,
.000025,.004004,
.000258,.003996,
.00044,.00398,
.00129,.00483,
.001007,.004897,
.000721,.004947,
.000432,.004981,
.000141,.004997,
-.000149,.004997,
-.00044,.00498,
-.000729,.004946,
-.001015,.004895,
-.00129,.00483,
-.00044,.00398,
270.*
%
%ADD30MACRO30*%
%AMMACRO15*
4,1,15,.00398,.00044,
.003999,.000208,
.004004,-.000025,
.003996,-.000258,
.00398,-.00044,
.00483,-.00129,
.004897,-.001007,
.004947,-.000721,
.004981,-.000432,
.004997,-.000141,
.004997,.000149,
.00498,.00044,
.004946,.000729,
.004895,.001015,
.00483,.00129,
.00398,.00044,
180.*
4,1,15,.00044,-.00398,
.000208,-.003999,
-.000025,-.004004,
-.000258,-.003996,
-.00044,-.00398,
-.00129,-.00483,
-.001007,-.004897,
-.000721,-.004947,
-.000432,-.004981,
-.000141,-.004997,
.000149,-.004997,
.00044,-.00498,
.000729,-.004946,
.001015,-.004895,
.00129,-.00483,
.00044,-.00398,
180.*
4,1,15,-.00398,-.00044,
-.003999,-.000208,
-.004004,.000025,
-.003996,.000258,
-.00398,.00044,
-.00483,.00129,
-.004897,.001007,
-.004947,.000721,
-.004981,.000432,
-.004997,.000141,
-.004997,-.000149,
-.00498,-.00044,
-.004946,-.000729,
-.004895,-.001015,
-.00483,-.00129,
-.00398,-.00044,
180.*
4,1,15,-.00044,.00398,
-.000208,.003999,
.000025,.004004,
.000258,.003996,
.00044,.00398,
.00129,.00483,
.001007,.004897,
.000721,.004947,
.000432,.004981,
.000141,.004997,
-.000149,.004997,
-.00044,.00498,
-.000729,.004946,
-.001015,.004895,
-.00129,.00483,
-.00044,.00398,
180.*
%
%ADD15MACRO15*%
%AMMACRO28*
4,1,15,-.00398,.00044,
-.003999,.000208,
-.004004,-.000025,
-.003996,-.000258,
-.00398,-.00044,
-.00483,-.00129,
-.004897,-.001007,
-.004947,-.000721,
-.004981,-.000432,
-.004997,-.000141,
-.004997,.000149,
-.00498,.00044,
-.004946,.000729,
-.004895,.001015,
-.00483,.00129,
-.00398,.00044,
270.*
4,1,15,-.00044,-.00398,
-.000208,-.003999,
.000025,-.004004,
.000258,-.003996,
.00044,-.00398,
.00129,-.00483,
.001007,-.004897,
.000721,-.004947,
.000432,-.004981,
.000141,-.004997,
-.000149,-.004997,
-.00044,-.00498,
-.000729,-.004946,
-.001015,-.004895,
-.00129,-.00483,
-.00044,-.00398,
270.*
4,1,15,.00398,-.00044,
.003999,-.000208,
.004004,.000025,
.003996,.000258,
.00398,.00044,
.00483,.00129,
.004897,.001007,
.004947,.000721,
.004981,.000432,
.004997,.000141,
.004997,-.000149,
.00498,-.00044,
.004946,-.000729,
.004895,-.001015,
.00483,-.00129,
.00398,-.00044,
270.*
4,1,15,.00044,.00398,
.000208,.003999,
-.000025,.004004,
-.000258,.003996,
-.00044,.00398,
-.00129,.00483,
-.001007,.004897,
-.000721,.004947,
-.000432,.004981,
-.000141,.004997,
.000149,.004997,
.00044,.00498,
.000729,.004946,
.001015,.004895,
.00129,.00483,
.00044,.00398,
270.*
%
%ADD28MACRO28*%
%AMMACRO27*
4,1,15,-.00398,.00044,
-.003999,.000208,
-.004004,-.000025,
-.003996,-.000258,
-.00398,-.00044,
-.00483,-.00129,
-.004897,-.001007,
-.004947,-.000721,
-.004981,-.000432,
-.004997,-.000141,
-.004997,.000149,
-.00498,.00044,
-.004946,.000729,
-.004895,.001015,
-.00483,.00129,
-.00398,.00044,
180.*
4,1,15,-.00044,-.00398,
-.000208,-.003999,
.000025,-.004004,
.000258,-.003996,
.00044,-.00398,
.00129,-.00483,
.001007,-.004897,
.000721,-.004947,
.000432,-.004981,
.000141,-.004997,
-.000149,-.004997,
-.00044,-.00498,
-.000729,-.004946,
-.001015,-.004895,
-.00129,-.00483,
-.00044,-.00398,
180.*
4,1,15,.00398,-.00044,
.003999,-.000208,
.004004,.000025,
.003996,.000258,
.00398,.00044,
.00483,.00129,
.004897,.001007,
.004947,.000721,
.004981,.000432,
.004997,.000141,
.004997,-.000149,
.00498,-.00044,
.004946,-.000729,
.004895,-.001015,
.00483,-.00129,
.00398,-.00044,
180.*
4,1,15,.00044,.00398,
.000208,.003999,
-.000025,.004004,
-.000258,.003996,
-.00044,.00398,
-.00129,.00483,
-.001007,.004897,
-.000721,.004947,
-.000432,.004981,
-.000141,.004997,
.000149,.004997,
.00044,.00498,
.000729,.004946,
.001015,.004895,
.00129,.00483,
.00044,.00398,
180.*
%
%ADD27MACRO27*%
%ADD46C,.02*%
%ADD47C,.006*%
%ADD53C,.06104*%
%ADD55C,.07704*%
%ADD54C,.11004*%
%ADD52C,.11104*%
%ADD60C,.13504*%
%ADD58C,.11704*%
%ADD57C,.11804*%
%ADD51C,.37504*%
%ADD50C,.29532*%
%ADD59C,.29533*%
%ADD56C,.23629*%
%ADD48O,.55202X.78802*%
%ADD64O,.09834X.04322*%
%ADD49O,.55204X.78804*%
%ADD63O,.09836X.04324*%
%ADD62O,.09854X.04342*%
%ADD61O,.09856X.04344*%
G75*
%LPD*%
G75*
G36*
G01X-6000Y-158756D02*
X1940843D01*
Y1664268D01*
X-6000D01*
Y-158756D01*
G37*
%LPC*%
G75*
G36*
G01X396575Y5000D02*
X5000D01*
Y10045D01*
G02X5657Y10351I400J0D01*
G03X29922Y21653I9500J11303D01*
G01Y21654D01*
G03X5657Y32956I-14765J-1D01*
G02X5000Y33262I-257J306D01*
G01Y462753D01*
G02X5657Y463059I400J-1D01*
G03X12306Y459885I9500J11350D01*
G03X18008I2851J10574D01*
G03Y488933I-2851J14524D01*
G03X12306I-2851J-10574D01*
G03X5657Y485759I2851J-14524D01*
G02X5000Y486065I-257J307D01*
G01Y1369803D01*
X746850D01*
G03X755787Y1378740I0J8937D01*
G01Y1463504D01*
X783465D01*
G03X792402Y1472441I0J8937D01*
G01Y1653268D01*
X904012D01*
X905934Y1651346D01*
Y1596315D01*
X882250Y1572631D01*
Y1549811D01*
X827250Y1494811D01*
Y1290311D01*
X821689Y1284750D01*
X771433D01*
G03X767567I-1933J-1250D01*
G01X687689D01*
X646189Y1243250D01*
X633848D01*
G02X633755Y1244039I0J400D01*
G03X654864Y1270866I-6492J26827D01*
G01Y1294466D01*
G03X599662I-27601J0D01*
G01Y1270866D01*
G03X620771Y1244039I27601J0D01*
G02X620678Y1243250I-93J-389D01*
G01X582689D01*
X562789Y1223350D01*
X418602D01*
G03X415198I-1702J-1550D01*
G01X26489D01*
X20750Y1217611D01*
Y1176689D01*
X55789Y1141650D01*
X59234D01*
X61250Y1139634D01*
Y650489D01*
X68316Y643423D01*
X110016D01*
X122189Y631250D01*
X135311D01*
X153022Y648961D01*
G02X153701Y648620I283J-282D01*
G03X182652Y649955I14606J-2163D01*
G02X183040Y650450I389J95D01*
G01X193162D01*
X203689Y639923D01*
X239016D01*
X247689Y631250D01*
X255811D01*
X273611Y649050D01*
X320562D01*
X327689Y641923D01*
X345311D01*
X350250Y646862D01*
Y946729D01*
X359138Y955617D01*
X607178D01*
X646311Y994750D01*
X680311D01*
X720750Y1035189D01*
Y1140074D01*
X722326Y1141650D01*
X817489D01*
X828750Y1130389D01*
Y883689D01*
X995750Y716689D01*
Y378487D01*
X995746Y378467D01*
G03Y377533I2254J-467D01*
G01X995750Y377513D01*
Y-79120D01*
X995749Y-79128D01*
G03Y-79472I2296J-172D01*
G01X995750Y-79480D01*
Y-84633D01*
X1003968Y-92851D01*
X1025954D01*
X1027839Y-94736D01*
Y-146312D01*
X1027826Y-146346D01*
G03X1027663Y-147343I2438J-910D01*
G02X1027264Y-147756I-400J-13D01*
G01X871142D01*
Y-11811D01*
G03X862205Y-2874I-8937J0D01*
G01X847835D01*
X847784Y-2751D01*
G03X843538I-2123J-891D01*
G01X843487Y-2874D01*
X835982D01*
X835941Y-2728D01*
G03X831507I-2217J-618D01*
G01X831466Y-2874D01*
X792341D01*
X792317Y-2702D01*
G03X783466Y5000I-8852J-1235D01*
G01X595551D01*
Y55118D01*
G03X586614Y64055I-8937J0D01*
G01X559990D01*
X559973Y64236D01*
G03X558860Y66171I-2690J-259D01*
G02X558811Y66778I234J324D01*
G03X559444Y68306I-1528J1528D01*
G01Y73819D01*
G03X555122I-2161J0D01*
G01Y68305D01*
G03X555755Y66778I2161J1D01*
G02X555706Y66171I-283J-283D01*
G03X554593Y64236I1577J-2194D01*
G01X554576Y64055D01*
X545817D01*
X545800Y64236D01*
G03X544687Y66171I-2690J-259D01*
G02X544638Y66778I234J324D01*
G03X545272Y68306I-1528J1529D01*
G01Y73819D01*
G03X540948I-2162J0D01*
G01Y68307D01*
G03X541582Y66778I2161J0D01*
G02X541533Y66171I-283J-283D01*
G03X540420Y64236I1577J-2194D01*
G01X540403Y64055D01*
X531644D01*
X531627Y64236D01*
G03X530514Y66171I-2690J-259D01*
G02X530465Y66778I234J324D01*
G03X531098Y68306I-1528J1528D01*
G01Y73819D01*
G03X526776I-2161J0D01*
G01Y68305D01*
G03X527409Y66778I2161J1D01*
G02X527360Y66171I-283J-283D01*
G03X526247Y64236I1577J-2194D01*
G01X526230Y64055D01*
X517471D01*
X517454Y64236D01*
G03X516341Y66171I-2690J-259D01*
G02X516292Y66778I234J324D01*
G03X516926Y68306I-1528J1529D01*
G01Y73819D01*
G03X512602I-2162J0D01*
G01Y68307D01*
G03X513236Y66778I2161J0D01*
G02X513187Y66171I-283J-283D01*
G03X512074Y64236I1577J-2194D01*
G01X512057Y64055D01*
X474951D01*
X474934Y64236D01*
G03X473821Y66171I-2690J-259D01*
G02X473772Y66778I234J324D01*
G03X474406Y68306I-1528J1529D01*
G01Y73819D01*
G03X470082I-2162J0D01*
G01Y68307D01*
G03X470716Y66778I2161J0D01*
G02X470667Y66171I-283J-283D01*
G03X469554Y64236I1577J-2194D01*
G01X469537Y64055D01*
X460778D01*
X460761Y64236D01*
G03X459648Y66171I-2690J-259D01*
G02X459599Y66778I234J324D01*
G03X460232Y68306I-1528J1528D01*
G01Y73819D01*
G03X455910I-2161J0D01*
G01Y68305D01*
G03X456543Y66778I2161J1D01*
G02X456494Y66171I-283J-283D01*
G03X455381Y64236I1577J-2194D01*
G01X455364Y64055D01*
X446605D01*
X446588Y64236D01*
G03X445475Y66171I-2690J-259D01*
G02X445426Y66778I234J324D01*
G03X446060Y68306I-1528J1529D01*
G01Y73819D01*
G03X441736I-2162J0D01*
G01Y68307D01*
G03X442370Y66778I2161J0D01*
G02X442321Y66171I-283J-283D01*
G03X441208Y64236I1577J-2194D01*
G01X441191Y64055D01*
X432431D01*
X432414Y64236D01*
G03X431301Y66171I-2690J-259D01*
G02X431252Y66778I234J324D01*
G03X431886Y68306I-1528J1529D01*
G01Y73819D01*
G03X427562I-2162J0D01*
G01Y68307D01*
G03X428196Y66778I2161J0D01*
G02X428147Y66171I-283J-283D01*
G03X427034Y64236I1577J-2194D01*
G01X427017Y64055D01*
X405512D01*
G03X396575Y55118I0J-8937D01*
G01Y5000D01*
G37*
G36*
G01X1069016Y-74923D02*
X1052588Y-91351D01*
X1026576D01*
X1026575Y-91350D01*
X1025953D01*
X1025952Y-91351D01*
X1004590D01*
X997250Y-84011D01*
Y454513D01*
X997254Y454533D01*
G03Y455467I-2254J467D01*
G01X997250Y455487D01*
Y487513D01*
X997254Y487533D01*
G03Y488467I-2254J467D01*
G01X997250Y488487D01*
Y717311D01*
X949846Y764715D01*
G03X949040Y765521I-1980J-1174D01*
G01X830250Y884311D01*
Y1131011D01*
X818111Y1143150D01*
X733334D01*
X733300Y1143162D01*
G03X731700I-800J-2158D01*
G01X731666Y1143150D01*
X680589D01*
X657250Y1119811D01*
Y1113311D01*
X628689Y1084750D01*
X623311D01*
X620750Y1087311D01*
Y1101689D01*
X647750Y1128689D01*
Y1138311D01*
X642911Y1143150D01*
X609121D01*
X609087Y1143162D01*
G03X607487I-800J-2158D01*
G01X607453Y1143150D01*
X508678D01*
G03X504722I-1978J-1177D01*
G01X484908D01*
X484874Y1143162D01*
G03X483274I-800J-2158D01*
G01X483240Y1143150D01*
X440352D01*
X440336Y1143333D01*
G03X402970I-18683J-1601D01*
G01X402954Y1143150D01*
X393369D01*
X393328Y1143296D01*
G03X388896I-2216J-623D01*
G01X388855Y1143150D01*
X366089D01*
X335189Y1112250D01*
X312689D01*
X285189Y1084750D01*
X250811D01*
X247750Y1087811D01*
Y1102811D01*
X227811Y1122750D01*
X169689D01*
X154011Y1107072D01*
X153888Y1107124D01*
G03X150876Y1104112I-888J-2124D01*
G01X150928Y1103989D01*
X131189Y1084250D01*
X126811D01*
X124250Y1086811D01*
Y1135311D01*
X116411Y1143150D01*
X112271D01*
X112237Y1143162D01*
G03X110637I-800J-2158D01*
G01X110603Y1143150D01*
X56411D01*
X22250Y1177311D01*
Y1216989D01*
X27111Y1221850D01*
X30677D01*
X30710Y1221838D01*
G03X32290I790J2162D01*
G01X32323Y1221850D01*
X563411D01*
X583311Y1241750D01*
X646811D01*
X688311Y1283250D01*
X767206D01*
X767236Y1283086D01*
G03X771764I2264J414D01*
G01X771794Y1283250D01*
X822311D01*
X828750Y1289689D01*
Y1494189D01*
X883750Y1549189D01*
Y1572009D01*
X906911Y1595170D01*
X915470D01*
X920934Y1589706D01*
Y1528495D01*
X888147Y1495708D01*
X888101Y1495693D01*
G03X886607Y1494199I699J-2193D01*
G01X886592Y1494153D01*
X867250Y1474811D01*
Y1432689D01*
X887230Y1412709D01*
X894887D01*
X902625Y1404971D01*
Y1397314D01*
X910250Y1389689D01*
Y1057649D01*
X910077Y1057625D01*
G03Y1053063I310J-2281D01*
G01X910250Y1053039D01*
Y1004038D01*
G03Y1000646I1557J-1696D01*
G01Y981493D01*
X910078Y981469D01*
G03Y976909I319J-2280D01*
G01X910250Y976885D01*
Y868689D01*
X1036250Y742689D01*
Y98016D01*
X1036246Y97996D01*
G03Y97090I2257J-453D01*
G01X1036250Y97070D01*
Y5689D01*
X1074750Y-32811D01*
Y-69189D01*
X1072223Y-71716D01*
X1072090Y-71637D01*
G03X1068937Y-74790I-1172J-1981D01*
G01X1069016Y-74923D01*
G37*
G36*
G01X122811Y632750D02*
X110638Y644923D01*
X68938D01*
X62750Y651111D01*
Y1139634D01*
X64766Y1141650D01*
X115789D01*
X122750Y1134689D01*
Y1086189D01*
X126189Y1082750D01*
X131811D01*
X151989Y1102928D01*
X152112Y1102876D01*
G03X155124Y1105888I888J2124D01*
G01X155072Y1106011D01*
X166401Y1117340D01*
G02X167050Y1116896I283J-283D01*
G03X175646Y1120477I6178J-2723D01*
G02X175789Y1121250I144J373D01*
G01X227189D01*
X246250Y1102189D01*
Y1087189D01*
X250189Y1083250D01*
X285811D01*
X313311Y1110750D01*
X335811D01*
X366711Y1141650D01*
X389050D01*
G03X393174I2062J1023D01*
G01X402901D01*
X402904Y1141453D01*
G03X440402I18749J279D01*
G01X440405Y1141650D01*
X504415D01*
X504449Y1141492D01*
G03X508951I2251J481D01*
G01X508985Y1141650D01*
X642289D01*
X646250Y1137689D01*
Y1129311D01*
X619250Y1102311D01*
Y1086689D01*
X622689Y1083250D01*
X629311D01*
X658750Y1112689D01*
Y1119189D01*
X681211Y1141650D01*
X717681D01*
X719250Y1140081D01*
Y1035811D01*
X679689Y996250D01*
X645689D01*
X606556Y957117D01*
X358516D01*
X348750Y947351D01*
Y647484D01*
X344689Y643423D01*
X328311D01*
X321184Y650550D01*
X272989D01*
X255189Y632750D01*
X248311D01*
X239638Y641423D01*
X204311D01*
X193784Y651950D01*
X182013D01*
G03X154652Y652074I-13706J-5493D01*
G01X154601Y651950D01*
X153889D01*
X134689Y632750D01*
X122811D01*
G37*
G36*
G01X911750Y1008154D02*
Y1053489D01*
G03Y1057199I-1363J1855D01*
G01Y1390311D01*
X904125Y1397936D01*
Y1405593D01*
X895509Y1414209D01*
X887852D01*
X868750Y1433311D01*
Y1474189D01*
X922434Y1527873D01*
Y1590328D01*
X916092Y1596670D01*
X912916D01*
G03X910706I-1105J-2575D01*
G01X908868D01*
X907434Y1598104D01*
Y1651514D01*
X909188Y1653268D01*
X960671D01*
X962335Y1651604D01*
Y1518642D01*
X989885Y1491092D01*
Y861254D01*
X1103150Y747989D01*
Y741111D01*
X1101389Y739350D01*
X1093916D01*
X1090777Y736211D01*
Y403109D01*
X1094862Y399024D01*
X1099453D01*
X1103376Y402947D01*
X1117070D01*
X1121197Y398820D01*
X1127218D01*
X1132560Y404162D01*
X1221746Y314976D01*
Y149693D01*
X1238552Y132887D01*
X1372006D01*
X1374076Y130816D01*
Y67299D01*
G02X1373885Y67099I-200J0D01*
G03X1371472Y63882I115J-2599D01*
G02X1371338Y63644I-194J-47D01*
G03X1365079Y55118I2678J-8526D01*
G01Y5000D01*
X1185039D01*
G03X1176102Y-3937I0J-8937D01*
G01Y-147756D01*
X1029339D01*
Y-94743D01*
X1031231Y-92851D01*
X1053210D01*
X1070240Y-75821D01*
X1070350Y-75849D01*
G03X1073149Y-73050I568J2231D01*
G01X1073121Y-72940D01*
X1076250Y-69811D01*
Y-40470D01*
G03Y-37730I-1850J1370D01*
G01Y-32189D01*
X1037750Y6311D01*
Y92044D01*
G03Y95042I-1747J1499D01*
G01Y743311D01*
X911750Y869311D01*
Y977327D01*
G03Y981051I-1353J1862D01*
G01Y981609D01*
X911780Y981657D01*
G03X911750Y984138I-1954J1217D01*
G01Y1005072D01*
G03Y1008154I-1710J1541D01*
G37*
G36*
G01X1456073Y103001D02*
G03Y118102I9085J7550D01*
G02X1455365Y118357I-308J255D01*
G01Y128696D01*
X1449674Y134387D01*
X1239174D01*
X1223246Y150315D01*
Y315598D01*
X1135389Y403455D01*
X1135812Y403877D01*
Y720986D01*
X1114946Y741852D01*
X1104650D01*
Y748611D01*
X991385Y861876D01*
Y1491714D01*
X963835Y1519264D01*
Y1562810D01*
G03Y1565590I-1835J1390D01*
G01Y1651574D01*
X965529Y1653268D01*
X1088910D01*
Y1590895D01*
X1127426Y1552380D01*
Y1445135D01*
X1129927Y1442633D01*
Y1423696D01*
X1066300D01*
X1059844Y1417240D01*
Y1128603D01*
X1063782Y1124666D01*
X1067025D01*
G03X1073285I3130J1237D01*
G01X1080225D01*
G03X1085384Y1123217I3130J1237D01*
G03X1089950Y1123160I2316J2583D01*
G03X1095478Y1124666I2250J2640D01*
G01X1112739D01*
G03X1117070Y1124093I2261J434D01*
G02X1117430I180J-88D01*
G03X1121761Y1124666I2070J1007D01*
G01X1121839D01*
G03X1126361I2261J434D01*
G01X1126539D01*
G03X1131061I2261J434D01*
G01X1135136D01*
G03X1139736I2300J84D01*
G01X1200390D01*
X1202892Y1127167D01*
X1328503D01*
X1330419Y1125251D01*
Y1081380D01*
X1321750Y1072711D01*
Y1051089D01*
X1330419Y1042420D01*
Y968302D01*
X1330287Y968255D01*
G03Y963925I783J-2165D01*
G01X1330419Y963878D01*
Y627529D01*
X1346357Y611591D01*
X1388931D01*
X1392306Y608216D01*
Y573679D01*
X1390255Y571628D01*
X1358456D01*
X1349162Y562334D01*
Y266223D01*
X1329750Y246811D01*
Y200689D01*
X1333789Y196650D01*
X1494989D01*
X1496750Y194888D01*
Y122712D01*
X1496626Y122662D01*
G03X1496302Y118844I815J-1992D01*
G02Y118165I-211J-340D01*
G03X1496626Y114347I1139J-1826D01*
G01X1496750Y114297D01*
Y112869D01*
X1496626Y112819D01*
G03X1496302Y109001I815J-1992D01*
G02Y108322I-211J-339D01*
G03Y104670I1139J-1826D01*
G02Y103992I-212J-339D01*
G03X1495763Y100818I1139J-1826D01*
G01X1495876Y100679D01*
X1487947Y92750D01*
X1485383D01*
X1485342Y92897D01*
G03X1481194I-2074J-574D01*
G01X1481153Y92750D01*
X1464843D01*
X1455365Y102228D01*
Y102746D01*
G02X1456073Y103001I400J-1D01*
G37*
G36*
G01X1198733Y1128667D02*
X1065439D01*
X1063846Y1130260D01*
Y1415583D01*
X1067957Y1419694D01*
X1132343D01*
X1140250Y1411787D01*
Y1188689D01*
X1199194Y1129745D01*
Y1129128D01*
X1198733Y1128667D01*
G37*
G36*
G01X1131810Y719329D02*
Y405534D01*
X1126596Y400320D01*
X1121819D01*
X1117692Y404447D01*
X1102754D01*
X1098831Y400524D01*
X1095484D01*
X1092277Y403731D01*
Y735589D01*
X1094538Y737850D01*
X1113289D01*
X1131810Y719329D01*
G37*
G36*
G01X1581257Y1115437D02*
X1568027Y1128667D01*
X1202394D01*
X1141750Y1189311D01*
Y1412409D01*
X1131427Y1422732D01*
Y1442238D01*
X1132939Y1443750D01*
X1159173D01*
Y1378740D01*
G03X1168110Y1369803I8937J0D01*
G01X1172049D01*
X1172050Y1369802D01*
Y1265389D01*
X1252689Y1184750D01*
X1591319D01*
X1591370Y1184626D01*
G03X1595630I2130J874D01*
G01X1595681Y1184750D01*
X1847189D01*
X1852250Y1179689D01*
Y1130547D01*
X1850376Y1128673D01*
X1849846D01*
X1849840Y1128667D01*
X1641830D01*
X1628600Y1115437D01*
X1581257D01*
G37*
G36*
G01X1092912Y1592552D02*
Y1649966D01*
G02X1093111Y1650166I200J0D01*
G03X1095699Y1652855I-13J2602D01*
G02X1096098Y1653268I400J13D01*
G01X1215472D01*
Y1477441D01*
X1168110D01*
G03X1159173Y1468504I0J-8937D01*
G01Y1445250D01*
X1132969D01*
X1131427Y1446792D01*
Y1554037D01*
X1092912Y1592552D01*
G37*
G36*
G01X1564055Y55118D02*
G03X1555118Y64055I-8937J0D01*
G01X1528494D01*
X1528477Y64236D01*
G03X1527364Y66171I-2690J-259D01*
G02X1527315Y66778I234J324D01*
G03X1527948Y68306I-1528J1528D01*
G01Y73819D01*
G03X1523626I-2161J0D01*
G01Y68305D01*
G03X1524259Y66778I2161J1D01*
G02X1524210Y66171I-283J-283D01*
G03X1523097Y64236I1577J-2194D01*
G01X1523080Y64055D01*
X1514321D01*
X1514304Y64236D01*
G03X1513191Y66171I-2690J-259D01*
G02X1513142Y66778I234J324D01*
G03X1513776Y68306I-1528J1529D01*
G01Y73819D01*
G03X1509452I-2162J0D01*
G01Y68307D01*
G03X1510086Y66778I2161J0D01*
G02X1510037Y66171I-283J-283D01*
G03X1508924Y64236I1577J-2194D01*
G01X1508907Y64055D01*
X1500148D01*
X1500131Y64236D01*
G03X1499018Y66171I-2690J-259D01*
G02X1498969Y66778I234J324D01*
G03X1499602Y68306I-1528J1528D01*
G01Y73819D01*
G03X1495280I-2161J0D01*
G01Y68305D01*
G03X1495913Y66778I2161J1D01*
G02X1495864Y66171I-283J-283D01*
G03X1494751Y64236I1577J-2194D01*
G01X1494734Y64055D01*
X1485975D01*
X1485958Y64236D01*
G03X1484845Y66171I-2690J-259D01*
G02X1484796Y66778I234J324D01*
G03X1485430Y68306I-1528J1529D01*
G01Y73819D01*
G03X1481106I-2162J0D01*
G01Y68307D01*
G03X1481740Y66778I2161J0D01*
G02X1481691Y66171I-283J-283D01*
G03X1480578Y64236I1577J-2194D01*
G01X1480561Y64055D01*
X1443455D01*
X1443438Y64236D01*
G03X1442325Y66171I-2690J-259D01*
G02X1442276Y66778I234J324D01*
G03X1442910Y68306I-1528J1529D01*
G01Y73819D01*
G03X1438586I-2162J0D01*
G01Y68307D01*
G03X1439220Y66778I2161J0D01*
G02X1439171Y66171I-283J-283D01*
G03X1438058Y64236I1577J-2194D01*
G01X1438041Y64055D01*
X1429282D01*
X1429265Y64236D01*
G03X1428152Y66171I-2690J-259D01*
G02X1428103Y66778I234J324D01*
G03X1428736Y68306I-1528J1528D01*
G01Y73819D01*
G03X1424414I-2161J0D01*
G01Y68305D01*
G03X1425047Y66778I2161J1D01*
G02X1424998Y66171I-283J-283D01*
G03X1423885Y64236I1577J-2194D01*
G01X1423868Y64055D01*
X1415109D01*
X1415092Y64236D01*
G03X1413979Y66171I-2690J-259D01*
G02X1413930Y66778I234J324D01*
G03X1414564Y68306I-1528J1529D01*
G01Y73819D01*
G03X1410240I-2162J0D01*
G01Y68307D01*
G03X1410874Y66778I2161J0D01*
G02X1410825Y66171I-283J-283D01*
G03X1409712Y64236I1577J-2194D01*
G01X1409695Y64055D01*
X1400935D01*
X1400918Y64236D01*
G03X1399805Y66171I-2690J-259D01*
G02X1399756Y66778I234J324D01*
G03X1400390Y68306I-1528J1529D01*
G01Y73819D01*
G03X1396066I-2162J0D01*
G01Y68307D01*
G03X1396700Y66778I2161J0D01*
G02X1396651Y66171I-283J-283D01*
G03X1395538Y64236I1577J-2194D01*
G01X1395521Y64055D01*
X1376923D01*
X1376600Y64378D01*
X1376602Y64462D01*
G03X1375576Y66570I-2602J37D01*
G01Y130986D01*
X1377477Y132887D01*
X1449052D01*
X1453865Y128074D01*
Y114019D01*
G03X1453856Y107112I11292J-3468D01*
G01X1453865Y107083D01*
Y101606D01*
X1464221Y91250D01*
X1480788D01*
G03X1481691Y90129I2480J1073D01*
G02X1481740Y89522I-234J-324D01*
G03X1481106Y87993I1527J-1529D01*
G01Y82481D01*
G03X1485430Y82480I2162J0D01*
G01Y87993D01*
G03X1484796Y89522I-2161J0D01*
G02X1484845Y90129I283J283D01*
G03X1485748Y91250I-1577J2194D01*
G01X1488192D01*
Y86418D01*
G03X1492516Y86417I2162J0D01*
G01Y91930D01*
G03X1491882Y93459I-2161J0D01*
G02X1491931Y94066I283J283D01*
G03X1492979Y95620I-1577J2194D01*
G01X1492992Y95674D01*
X1497334Y100015D01*
X1497418Y100014D01*
G03X1498962Y103689I23J2152D01*
G02X1499012Y104297I282J283D01*
G03X1499011Y108695I-1571J2199D01*
G02X1498961Y109304I232J326D01*
G03X1498250Y112821I-1520J1523D01*
G01Y114345D01*
G03X1498961Y117862I-809J1994D01*
G02X1499011Y118471I282J283D01*
G03X1498380Y123203I-1570J2199D01*
G01X1498250Y123252D01*
Y194694D01*
X1500206Y196650D01*
X1524721D01*
G03X1527341I1310J1893D01*
G01X1560189D01*
X1561622Y195217D01*
X1561626Y195140D01*
G03X1563804Y192962I2299J121D01*
G01X1563881Y192958D01*
X1598672Y158167D01*
X1843230D01*
X1843263Y158008D01*
G03X1847771I2254J467D01*
G01X1847804Y158167D01*
X1863028D01*
X1875450Y170589D01*
Y188489D01*
X1886150Y199189D01*
Y432589D01*
X1913419Y459858D01*
Y793141D01*
G03Y814733I-10072J10796D01*
G01Y834312D01*
G03Y838576I-868J2132D01*
G01Y839812D01*
G03Y844076I-868J2132D01*
G01Y847992D01*
X1910441Y850970D01*
X1831709D01*
X1825959Y845220D01*
G02X1825280Y845449I-283J283D01*
G03X1770332Y841710I-27347J-3739D01*
G01Y818110D01*
G03X1803595Y791096I27601J0D01*
G02X1803960Y790421I83J-392D01*
G01X1765889Y752350D01*
X1710189D01*
X1701419Y743580D01*
Y518842D01*
X1696258Y513681D01*
X1609834D01*
X1607044Y510891D01*
Y301105D01*
X1588816Y282877D01*
X1352396D01*
X1350662Y284611D01*
Y561712D01*
X1359078Y570128D01*
X1390877D01*
X1393806Y573057D01*
Y608838D01*
X1389553Y613091D01*
X1346979D01*
X1331919Y628151D01*
Y643110D01*
X1333476Y644667D01*
X1351484D01*
X1351508Y644494D01*
G03X1380902Y646853I14634J1963D01*
G01X1380900Y646939D01*
X1386611Y652650D01*
X1453375D01*
X1461358Y644667D01*
X1525509D01*
G02X1525806Y644000I-1J-400D01*
G03X1525423Y642962I1119J-1002D01*
G01X1525424Y642959D01*
Y638537D01*
X1525423Y638534D01*
G03X1528427I1502J-36D01*
G01X1528426Y638537D01*
Y642959D01*
X1528427Y642962D01*
G03X1528044Y644000I-1502J36D01*
G02X1528341Y644667I298J267D01*
G01X1583480D01*
X1587424Y648611D01*
G02X1588105Y648303I282J-283D01*
G03X1588156Y644244I14651J-1846D01*
G03X1614241Y637175I14599J2210D01*
G03X1589172Y652246I-11485J9282D01*
G02X1588419Y652435I-353J189D01*
G01Y910136D01*
G03Y914264I-1019J2064D01*
G01Y928318D01*
X1616988Y956887D01*
X1868233D01*
X1874054Y962708D01*
Y1021471D01*
X1891419Y1038836D01*
Y1109728D01*
X1872480Y1128667D01*
X1855466D01*
X1853750Y1130383D01*
Y1180311D01*
X1847811Y1186250D01*
X1595681D01*
X1595630Y1186374D01*
G03X1591370I-2130J-874D01*
G01X1591319Y1186250D01*
X1253311D01*
X1173550Y1266011D01*
Y1369803D01*
X1929843D01*
Y5000D01*
X1564055D01*
Y55118D01*
G37*
G36*
G01X1461980Y646167D02*
X1453997Y654150D01*
X1385989D01*
X1381242Y649403D01*
G02X1380569Y649601I-282J283D01*
G03X1351377Y646368I-14427J-3144D01*
G01Y646167D01*
X1333476D01*
X1331919Y647724D01*
Y963950D01*
G03Y968230I-849J2140D01*
G01Y1043042D01*
X1323250Y1051711D01*
Y1072089D01*
X1331919Y1080758D01*
Y1125251D01*
X1333835Y1127167D01*
X1567405D01*
X1580635Y1113937D01*
X1629222D01*
X1642452Y1127167D01*
X1871858D01*
X1889919Y1109106D01*
Y1039458D01*
X1872554Y1022093D01*
Y963330D01*
X1867611Y958387D01*
X1851386D01*
G03X1849140I-1123J-2347D01*
G01X1846886D01*
G03X1844640I-1123J-2347D01*
G01X1616366D01*
X1586919Y928940D01*
Y914456D01*
X1586773Y914415D01*
G03Y909985I627J-2215D01*
G01X1586919Y909944D01*
Y650228D01*
X1582858Y646167D01*
X1461980D01*
G37*
G36*
G01X1823587Y807926D02*
X1824850Y809189D01*
Y812001D01*
X1824855Y812023D01*
G03X1825534Y818105I-26922J6085D01*
G01Y841710D01*
G03X1825521Y842571I-27601J14D01*
G01X1825518Y842657D01*
X1832331Y849470D01*
X1909819D01*
X1911919Y847370D01*
Y844162D01*
X1911786Y844115D01*
G03Y839773I765J-2171D01*
G01X1911919Y839726D01*
Y838662D01*
X1911786Y838615D01*
G03Y834273I765J-2171D01*
G01X1911919Y834226D01*
Y816711D01*
G02X1911303Y816375I-400J1D01*
G03Y791499I-7956J-12438D01*
G02X1911919Y791163I216J-337D01*
G01Y460480D01*
X1884650Y433211D01*
Y199811D01*
X1873950Y189111D01*
Y171211D01*
X1862406Y159667D01*
X1847486D01*
G03X1843548I-1969J-1192D01*
G01X1599294D01*
X1560811Y198150D01*
X1334411D01*
X1331250Y201311D01*
Y246189D01*
X1350662Y265601D01*
Y279614D01*
X1352425Y281377D01*
X1589438D01*
X1608544Y300483D01*
Y510269D01*
X1610456Y512181D01*
X1696880D01*
X1702919Y518220D01*
Y742958D01*
X1710811Y750850D01*
X1766511D01*
X1808117Y792456D01*
X1808155Y792471D01*
G03X1823572Y807888I-10222J25639D01*
G01X1823587Y807926D01*
G37*
%LPD*%
G75*
G36*
G01X956203Y534842D02*
X956208Y534833D01*
X948330Y530894D01*
X948327Y530899D01*
X948229Y530857D01*
G02X945676Y535977I-1183J2607D01*
G01X945762Y536027D01*
X945760Y536032D01*
X953637Y539971D01*
X953643Y539965D01*
X953704Y539992D01*
G02X956203Y534842I1217J-2591D01*
G37*
G36*
G01Y424606D02*
X956208Y424597D01*
X948330Y420658D01*
X948327Y420663D01*
X948229Y420621D01*
G02X945676Y425741I-1183J2607D01*
G01X945762Y425791D01*
X945760Y425796D01*
X953637Y429735D01*
X953643Y429729D01*
X953704Y429756D01*
G02X956203Y424606I1217J-2591D01*
G37*
G36*
G01X907745Y-40121D02*
G02X902097I-2824J10580D01*
G02Y-11061I2824J14530D01*
G02X907745I2824J-10580D01*
G02Y-40121I-2824J-14530D01*
G37*
G36*
G01X956156Y708159D02*
X948315Y704239D01*
X948314Y704238D01*
G02X945812Y709162I-1267J2454D01*
G01X953686Y713099D01*
G02X956156Y708159I1235J-2470D01*
G37*
G36*
G01Y660915D02*
X948315Y656995D01*
X948314Y656994D01*
G02X945812Y661918I-1267J2454D01*
G01X953686Y665855D01*
G02X956156Y660915I1235J-2470D01*
G37*
G36*
G01Y692411D02*
X948315Y688491D01*
X948314Y688490D01*
G02X945812Y693414I-1267J2454D01*
G01X953686Y697351D01*
G02X956156Y692411I1235J-2470D01*
G37*
G36*
G01Y676663D02*
X948315Y672743D01*
X948314Y672742D01*
G02X945812Y677666I-1267J2454D01*
G01X953686Y681603D01*
G02X956156Y676663I1235J-2470D01*
G37*
G36*
G01X956210Y645060D02*
X948337Y641123D01*
G02X945758Y646277I-1290J2577D01*
G01X953632Y650214D01*
G02X956210Y645060I1289J-2577D01*
G37*
G36*
G01X945758Y630529D02*
X953631Y634466D01*
G02X956210Y629312I1290J-2577D01*
G01X948336Y625375D01*
G02X945758Y630529I-1289J2577D01*
G37*
G36*
G01Y614781D02*
X953631Y618718D01*
G02X956210Y613564I1290J-2577D01*
G01X948336Y609627D01*
G02X945758Y614781I-1289J2577D01*
G37*
G36*
G01X956210Y597816D02*
X948337Y593879D01*
G02X945758Y599033I-1290J2577D01*
G01X953632Y602970D01*
G02X956210Y597816I1289J-2577D01*
G37*
G36*
G01X956223Y503301D02*
X948392Y499386D01*
G02X945745Y504572I-1345J2582D01*
G01X953619Y508509D01*
G02X956223Y503301I1302J-2604D01*
G37*
G36*
G01X945745Y488824D02*
X953576Y492739D01*
G02X956223Y487553I1345J-2582D01*
G01X948349Y483616D01*
G02X945745Y488824I-1302J2604D01*
G37*
G36*
G01X945758Y473049D02*
X953631Y476986D01*
G02X956210Y471832I1290J-2577D01*
G01X948336Y467895D01*
G02X945758Y473049I-1289J2577D01*
G37*
G36*
G01X956210Y456084D02*
X948337Y452147D01*
G02X945758Y457301I-1290J2577D01*
G01X953632Y461238D01*
G02X956210Y456084I1289J-2577D01*
G37*
G36*
G01X945812Y314281D02*
X953653Y318201D01*
X953654Y318202D01*
G02X956156Y313278I1267J-2454D01*
G01X948282Y309341D01*
G02X945812Y314281I-1235J2470D01*
G37*
G36*
G01X956156Y329026D02*
X948315Y325106D01*
X948314Y325105D01*
G02X945812Y330029I-1267J2454D01*
G01X953686Y333966D01*
G02X956156Y329026I1235J-2470D01*
G37*
G36*
G01Y266034D02*
X948315Y262114D01*
X948314Y262113D01*
G02X945812Y267037I-1267J2454D01*
G01X953686Y270974D01*
G02X956156Y266034I1235J-2470D01*
G37*
G36*
G01X945812Y282785D02*
X953653Y286705D01*
X953654Y286706D01*
G02X956156Y281782I1267J-2454D01*
G01X948282Y277845D01*
G02X945812Y282785I-1235J2470D01*
G37*
G36*
G01Y298533D02*
X953653Y302453D01*
X953654Y302454D01*
G02X956156Y297530I1267J-2454D01*
G01X948282Y293593D01*
G02X945812Y298533I-1235J2470D01*
G37*
G36*
G01X956156Y218790D02*
X948315Y214870D01*
X948314Y214869D01*
G02X945812Y219793I-1267J2454D01*
G01X953686Y223730D01*
G02X956156Y218790I1235J-2470D01*
G37*
G36*
G01Y234538D02*
X948315Y230618D01*
X948314Y230617D01*
G02X945812Y235541I-1267J2454D01*
G01X953686Y239478D01*
G02X956156Y234538I1235J-2470D01*
G37*
G36*
G01Y250286D02*
X948315Y246366D01*
X948314Y246365D01*
G02X945812Y251289I-1267J2454D01*
G01X953686Y255226D01*
G02X956156Y250286I1235J-2470D01*
G37*
G36*
G01Y171546D02*
X948315Y167626D01*
X948314Y167625D01*
G02X945812Y172549I-1267J2454D01*
G01X953686Y176486D01*
G02X956156Y171546I1235J-2470D01*
G37*
G36*
G01Y187294D02*
X948315Y183374D01*
X948314Y183373D01*
G02X945812Y188297I-1267J2454D01*
G01X953686Y192234D01*
G02X956156Y187294I1235J-2470D01*
G37*
G36*
G01X945812Y204045D02*
X953653Y207965D01*
X953654Y207966D01*
G02X956156Y203042I1267J-2454D01*
G01X948282Y199105D01*
G02X945812Y204045I-1235J2470D01*
G37*
G36*
G01X945762Y141151D02*
X953636Y145088D01*
G02X956206Y139952I1285J-2568D01*
G01X948332Y136015D01*
G02X945762Y141151I-1285J2568D01*
G37*
G36*
G01X956156Y155798D02*
X948315Y151878D01*
X948314Y151877D01*
G02X945812Y156801I-1267J2454D01*
G01X953686Y160738D01*
G02X956156Y155798I1235J-2470D01*
G37*
G36*
G01X936089Y696183D02*
X935924Y696253D01*
X935922Y696249D01*
X928046Y700187D01*
Y700195D01*
X927943Y700252D01*
G02X930447Y705390I1388J2503D01*
G01X930612Y705320D01*
X930614Y705324D01*
X938491Y701386D01*
X938489Y701382D01*
X938657Y701283D01*
G02X936089Y696183I-1453J-2465D01*
G37*
G36*
G01Y680435D02*
X935924Y680505D01*
X935922Y680501D01*
X928046Y684439D01*
Y684447D01*
X927943Y684504D01*
G02X930447Y689642I1388J2503D01*
G01X930612Y689572D01*
X930614Y689576D01*
X938491Y685638D01*
X938489Y685634D01*
X938657Y685535D01*
G02X936089Y680435I-1453J-2465D01*
G37*
G36*
G01Y664687D02*
X935924Y664757D01*
X935922Y664753D01*
X928046Y668691D01*
Y668699D01*
X927943Y668756D01*
G02X930447Y673894I1388J2503D01*
G01X930612Y673824D01*
X930614Y673828D01*
X938491Y669890D01*
X938489Y669886D01*
X938657Y669787D01*
G02X936089Y664687I-1453J-2465D01*
G37*
G36*
G01Y648939D02*
X935924Y649009D01*
X935922Y649005D01*
X928046Y652943D01*
Y652951D01*
X927943Y653008D01*
G02X930447Y658146I1388J2503D01*
G01X930612Y658076D01*
X930614Y658080D01*
X938491Y654142D01*
X938489Y654138D01*
X938657Y654039D01*
G02X936089Y648939I-1453J-2465D01*
G37*
G36*
G01X935916Y601753D02*
X928085Y605669D01*
X928084D01*
G02X930620Y610844I1248J2597D01*
G01X938494Y606907D01*
G02X935916Y601753I-1289J-2577D01*
G37*
G36*
G01Y633249D02*
X928085Y637165D01*
X928084D01*
G02X930620Y642340I1248J2597D01*
G01X938494Y638403D01*
G02X935916Y633249I-1289J-2577D01*
G37*
G36*
G01Y617501D02*
X928085Y621417D01*
X928084D01*
G02X930620Y626592I1248J2597D01*
G01X938494Y622655D01*
G02X935916Y617501I-1289J-2577D01*
G37*
G36*
G01Y586005D02*
X928085Y589921D01*
X928084D01*
G02X930620Y595096I1248J2597D01*
G01X938494Y591159D01*
G02X935916Y586005I-1289J-2577D01*
G37*
G36*
G01Y507265D02*
X928085Y511181D01*
X928084D01*
G02X930620Y516356I1248J2597D01*
G01X938494Y512419D01*
G02X935916Y507265I-1289J-2577D01*
G37*
G36*
G01X936089Y538703D02*
X935924Y538773D01*
X935922Y538769D01*
X928046Y542707D01*
Y542715D01*
X927943Y542772D01*
G02X930447Y547910I1388J2503D01*
G01X930612Y547840D01*
X930614Y547844D01*
X938491Y543906D01*
X938489Y543902D01*
X938657Y543803D01*
G02X936089Y538703I-1453J-2465D01*
G37*
G36*
G01X935916Y491517D02*
X928085Y495433D01*
X928084D01*
G02X930620Y500608I1248J2597D01*
G01X938494Y496671D01*
G02X935916Y491517I-1289J-2577D01*
G37*
G36*
G01X930620Y484860D02*
X938451Y480944D01*
X938452D01*
G02X935916Y475769I-1248J-2597D01*
G01X928042Y479706D01*
G02X930620Y484860I1289J2577D01*
G37*
G36*
G01X935916Y460021D02*
X928085Y463937D01*
X928084D01*
G02X930620Y469112I1248J2597D01*
G01X938494Y465175D01*
G02X935916Y460021I-1289J-2577D01*
G37*
G36*
G01Y444273D02*
X928085Y448189D01*
X928084D01*
G02X930620Y453364I1248J2597D01*
G01X938494Y449427D01*
G02X935916Y444273I-1289J-2577D01*
G37*
G36*
G01X936089Y317050D02*
X935924Y317120D01*
X935922Y317116D01*
X928046Y321054D01*
Y321062D01*
X927943Y321119D01*
G02X930447Y326257I1388J2503D01*
G01X930612Y326187D01*
X930614Y326191D01*
X938491Y322253D01*
X938489Y322249D01*
X938657Y322150D01*
G02X936089Y317050I-1453J-2465D01*
G37*
G36*
G01Y269806D02*
X935924Y269876D01*
X935922Y269872D01*
X928046Y273810D01*
Y273818D01*
X927943Y273875D01*
G02X930447Y279013I1388J2503D01*
G01X930612Y278943D01*
X930614Y278947D01*
X938491Y275009D01*
X938489Y275005D01*
X938657Y274906D01*
G02X936089Y269806I-1453J-2465D01*
G37*
G36*
G01Y301302D02*
X935924Y301372D01*
X935922Y301368D01*
X928046Y305306D01*
Y305314D01*
X927943Y305371D01*
G02X930447Y310509I1388J2503D01*
G01X930612Y310439D01*
X930614Y310443D01*
X938491Y306505D01*
X938489Y306501D01*
X938657Y306402D01*
G02X936089Y301302I-1453J-2465D01*
G37*
G36*
G01Y285554D02*
X935924Y285624D01*
X935922Y285620D01*
X928046Y289558D01*
Y289566D01*
X927943Y289623D01*
G02X930447Y294761I1388J2503D01*
G01X930612Y294691D01*
X930614Y294695D01*
X938491Y290757D01*
X938489Y290753D01*
X938657Y290654D01*
G02X936089Y285554I-1453J-2465D01*
G37*
G36*
G01Y222562D02*
X935924Y222632D01*
X935922Y222628D01*
X928046Y226566D01*
Y226574D01*
X927943Y226631D01*
G02X930447Y231769I1388J2503D01*
G01X930612Y231699D01*
X930614Y231703D01*
X938491Y227765D01*
X938489Y227761D01*
X938657Y227662D01*
G02X936089Y222562I-1453J-2465D01*
G37*
G36*
G01Y254058D02*
X935924Y254128D01*
X935922Y254124D01*
X928045Y258062D01*
X928047Y258066D01*
X927879Y258165D01*
G02X930447Y263265I1453J2465D01*
G01X930612Y263195D01*
X930614Y263199D01*
X938490Y259261D01*
Y259253D01*
X938593Y259196D01*
G02X936089Y254058I-1388J-2503D01*
G37*
G36*
G01Y238310D02*
X935924Y238380D01*
X935922Y238376D01*
X928046Y242314D01*
Y242322D01*
X927943Y242379D01*
G02X930447Y247517I1388J2503D01*
G01X930612Y247447D01*
X930614Y247451D01*
X938491Y243513D01*
X938489Y243509D01*
X938657Y243410D01*
G02X936089Y238310I-1453J-2465D01*
G37*
G36*
G01Y175318D02*
X935924Y175388D01*
X935922Y175384D01*
X928046Y179322D01*
Y179330D01*
X927943Y179387D01*
G02X930447Y184525I1388J2503D01*
G01X930612Y184455D01*
X930614Y184459D01*
X938491Y180521D01*
X938489Y180517D01*
X938657Y180418D01*
G02X936089Y175318I-1453J-2465D01*
G37*
G36*
G01Y191066D02*
X935924Y191136D01*
X935922Y191132D01*
X928046Y195070D01*
Y195078D01*
X927943Y195135D01*
G02X930447Y200273I1388J2503D01*
G01X930612Y200203D01*
X930614Y200207D01*
X938491Y196269D01*
X938489Y196265D01*
X938657Y196166D01*
G02X936089Y191066I-1453J-2465D01*
G37*
G36*
G01Y206814D02*
X935924Y206884D01*
X935922Y206880D01*
X928046Y210818D01*
Y210826D01*
X927943Y210883D01*
G02X930447Y216021I1388J2503D01*
G01X930612Y215951D01*
X930614Y215955D01*
X938491Y212017D01*
X938489Y212013D01*
X938657Y211914D01*
G02X936089Y206814I-1453J-2465D01*
G37*
G36*
G01Y159570D02*
X935924Y159640D01*
X935922Y159636D01*
X928046Y163574D01*
Y163582D01*
X927943Y163639D01*
G02X930447Y168777I1388J2503D01*
G01X930612Y168707D01*
X930614Y168711D01*
X938491Y164773D01*
X938489Y164769D01*
X938657Y164670D01*
G02X936089Y159570I-1453J-2465D01*
G37*
G36*
G01Y143822D02*
X935924Y143892D01*
X935922Y143888D01*
X928046Y147826D01*
Y147834D01*
X927943Y147891D01*
G02X930447Y153029I1388J2503D01*
G01X930612Y152959D01*
X930614Y152963D01*
X938491Y149025D01*
X938489Y149021D01*
X938657Y148922D01*
G02X936089Y143822I-1453J-2465D01*
G37*
G36*
G01X930620Y50609D02*
X938494Y46672D01*
G02X935916Y41518I-1289J-2577D01*
G01X928085Y45434D01*
X928084D01*
G02X930620Y50609I1248J2597D01*
G37*
G36*
G01X936089Y65082D02*
X935924Y65152D01*
X935922Y65148D01*
X928046Y69086D01*
Y69094D01*
X927943Y69151D01*
G02X930447Y74289I1388J2503D01*
G01X930612Y74219D01*
X930614Y74223D01*
X938491Y70285D01*
X938489Y70281D01*
X938657Y70182D01*
G02X936089Y65082I-1453J-2465D01*
G37*
G36*
G01X878540Y1646457D02*
Y1640944D01*
G02X874216Y1640945I-2162J1D01*
G01Y1646457D01*
G02X878540I2162J0D01*
G37*
G36*
G01X871454Y1636221D02*
Y1630708D01*
G02X867130Y1630709I-2162J1D01*
G01Y1636221D01*
G02X871454I2162J0D01*
G37*
G36*
G01X864366Y1646457D02*
Y1640944D01*
G02X860044Y1640945I-2161J1D01*
G01Y1646457D01*
G02X864366I2161J0D01*
G37*
G36*
G01X857280Y1636221D02*
Y1630708D01*
G02X852956Y1630709I-2162J1D01*
G01Y1636221D01*
G02X857280I2162J0D01*
G37*
G36*
G01X850194Y1646457D02*
Y1640944D01*
G02X845870Y1640945I-2162J1D01*
G01Y1646457D01*
G02X850194I2162J0D01*
G37*
G36*
G01X878540Y1603937D02*
Y1598424D01*
G02X874216Y1598425I-2162J1D01*
G01Y1603937D01*
G02X878540I2162J0D01*
G37*
G36*
G01X871454Y1607874D02*
Y1602362D01*
G02X867130Y1602363I-2162J1D01*
G01Y1607874D01*
G02X871454I2162J0D01*
G37*
G36*
G01X864366Y1603937D02*
Y1598424D01*
G02X860044Y1598425I-2161J1D01*
G01Y1603937D01*
G02X864366I2161J0D01*
G37*
G36*
G01X857280Y1607874D02*
Y1602362D01*
G02X852956Y1602363I-2162J1D01*
G01Y1607874D01*
G02X857280I2162J0D01*
G37*
G36*
G01X850194Y1603937D02*
Y1598424D01*
G02X845870Y1598425I-2162J1D01*
G01Y1603937D01*
G02X850194I2162J0D01*
G37*
G36*
G01X843106Y1636221D02*
Y1630708D01*
G02X838784Y1630709I-2161J1D01*
G01Y1636221D01*
G02X843106I2161J0D01*
G37*
G36*
G01X836020Y1646457D02*
Y1640944D01*
G02X831698Y1640945I-2161J1D01*
G01Y1646457D01*
G02X836020I2161J0D01*
G37*
G36*
G01X828934Y1636221D02*
Y1630708D01*
G02X824610Y1630709I-2162J1D01*
G01Y1636221D01*
G02X828934I2162J0D01*
G37*
G36*
G01Y1622048D02*
Y1616535D01*
G02X824610Y1616536I-2162J1D01*
G01Y1622048D01*
G02X828934I2162J0D01*
G37*
G36*
G01X843106Y1607874D02*
Y1602362D01*
G02X838784Y1602363I-2161J1D01*
G01Y1607874D01*
G02X843106I2161J0D01*
G37*
G36*
G01X836020Y1603937D02*
Y1598424D01*
G02X831698Y1598425I-2161J1D01*
G01Y1603937D01*
G02X836020I2161J0D01*
G37*
G36*
G01X828934Y1607874D02*
Y1602362D01*
G02X824610Y1602363I-2162J1D01*
G01Y1607874D01*
G02X828934I2162J0D01*
G37*
G36*
G01X566532Y91930D02*
Y86417D01*
G02X562208Y86418I-2162J1D01*
G01Y91930D01*
G02X566532I2162J0D01*
G37*
G36*
G01Y77756D02*
Y72244D01*
G02X562208Y72245I-2162J1D01*
G01Y77756D01*
G02X566532I2162J0D01*
G37*
G36*
G01Y120276D02*
Y114763D01*
G02X562208Y114764I-2162J1D01*
G01Y120276D01*
G02X566532I2162J0D01*
G37*
G36*
G01X519688Y72245D02*
Y77757D01*
G02X524012Y77756I2162J-1D01*
G01Y72245D01*
G02X519688I-2162J0D01*
G37*
G36*
G01X516926Y87993D02*
Y82480D01*
G02X512602Y82481I-2162J1D01*
G01Y87993D01*
G02X516926I2162J0D01*
G37*
G36*
G01X524012Y91930D02*
Y86417D01*
G02X519688Y86418I-2162J1D01*
G01Y91930D01*
G02X524012I2162J0D01*
G37*
G36*
G01X531098Y87993D02*
Y82480D01*
G02X526776Y82481I-2161J1D01*
G01Y87993D01*
G02X531098I2161J0D01*
G37*
G36*
G01X538186Y91930D02*
Y86417D01*
G02X533862Y86418I-2162J1D01*
G01Y91930D01*
G02X538186I2162J0D01*
G37*
G36*
G01Y77756D02*
Y72244D01*
G02X533862Y72245I-2162J1D01*
G01Y77756D01*
G02X538186I2162J0D01*
G37*
G36*
G01Y120276D02*
Y114763D01*
G02X533862Y114764I-2162J1D01*
G01Y120276D01*
G02X538186I2162J0D01*
G37*
G36*
G01X545272Y87993D02*
Y82480D01*
G02X540948Y82481I-2162J1D01*
G01Y87993D01*
G02X545272I2162J0D01*
G37*
G36*
G01X552358Y91930D02*
Y86417D01*
G02X548036Y86418I-2161J1D01*
G01Y91930D01*
G02X552358I2161J0D01*
G37*
G36*
G01X559444Y87993D02*
Y82480D01*
G02X555122Y82481I-2161J1D01*
G01Y87993D01*
G02X559444I2161J0D01*
G37*
G36*
G01X552358Y77756D02*
Y72244D01*
G02X548036Y72245I-2161J1D01*
G01Y77756D01*
G02X552358I2161J0D01*
G37*
G36*
G01X481492Y91930D02*
Y86417D01*
G02X477170Y86418I-2161J1D01*
G01Y91930D01*
G02X481492I2161J0D01*
G37*
G36*
G01Y77756D02*
Y72244D01*
G02X477170Y72245I-2161J1D01*
G01Y77756D01*
G02X481492I2161J0D01*
G37*
G36*
G01X467318Y91930D02*
Y86417D01*
G02X462996Y86418I-2161J1D01*
G01Y91930D01*
G02X467318I2161J0D01*
G37*
G36*
G01X474406Y87993D02*
Y82480D01*
G02X470082Y82481I-2162J1D01*
G01Y87993D01*
G02X474406I2162J0D01*
G37*
G36*
G01X467318Y77756D02*
Y72244D01*
G02X462996Y72245I-2161J1D01*
G01Y77756D01*
G02X467318I2161J0D01*
G37*
G36*
G01X477160Y114764D02*
Y120277D01*
G02X481502Y120276I2171J-1D01*
G01Y114764D01*
G02X477160I-2171J0D01*
G37*
G36*
G01X438972Y77756D02*
Y72244D01*
G02X434650Y72245I-2161J1D01*
G01Y77756D01*
G02X438972I2161J0D01*
G37*
G36*
G01X431886Y87993D02*
Y82480D01*
G02X427562Y82481I-2162J1D01*
G01Y87993D01*
G02X431886I2162J0D01*
G37*
G36*
G01X438972Y91930D02*
Y86417D01*
G02X434650Y86418I-2161J1D01*
G01Y91930D01*
G02X438972I2161J0D01*
G37*
G36*
G01X446060Y87993D02*
Y82480D01*
G02X441736Y82481I-2162J1D01*
G01Y87993D01*
G02X446060I2162J0D01*
G37*
G36*
G01X453146Y91930D02*
Y86417D01*
G02X448822Y86418I-2162J1D01*
G01Y91930D01*
G02X453146I2162J0D01*
G37*
G36*
G01X460232Y87993D02*
Y82480D01*
G02X455910Y82481I-2161J1D01*
G01Y87993D01*
G02X460232I2161J0D01*
G37*
G36*
G01X453146Y77756D02*
Y72244D01*
G02X448822Y72245I-2162J1D01*
G01Y77756D01*
G02X453146I2162J0D01*
G37*
G36*
G01X460232Y116339D02*
Y110826D01*
G02X455910Y110827I-2161J1D01*
G01Y116339D01*
G02X460232I2161J0D01*
G37*
G36*
G01X747549Y1091290D02*
X747550Y1091293D01*
Y1095715D01*
X747549Y1095718D01*
G02X750553I1502J36D01*
G01X750552Y1095715D01*
Y1091293D01*
X750553Y1091290D01*
G02X747549I-1502J-36D01*
G37*
G36*
G01Y638534D02*
X747550Y638537D01*
Y642959D01*
X747549Y642962D01*
G02X750553I1502J36D01*
G01X750552Y642959D01*
Y638537D01*
X750553Y638534D01*
G02X747549I-1502J-36D01*
G37*
G36*
G01X626340Y642962D02*
Y638534D01*
G02X623336I-1502J-36D01*
G01Y642962D01*
G02X626340I1502J36D01*
G37*
G36*
G01X499123Y638534D02*
X499124Y638537D01*
Y642959D01*
X499123Y642962D01*
G02X502127I1502J36D01*
G01X502126Y642959D01*
Y638537D01*
X502127Y638534D01*
G02X499123I-1502J-36D01*
G37*
G36*
G01X374911D02*
X374912Y638537D01*
Y642959D01*
X374911Y642962D01*
G02X377915I1502J36D01*
G01X377914Y642959D01*
Y638537D01*
X377915Y638534D01*
G02X374911I-1502J-36D01*
G37*
G36*
G01X747549Y185778D02*
X747550Y185781D01*
Y190203D01*
X747549Y190206D01*
G02X750553I1502J36D01*
G01X750552Y190203D01*
Y185781D01*
X750553Y185778D01*
G02X747549I-1502J-36D01*
G37*
G36*
G01X848249Y57017D02*
X848257Y56947D01*
X850146Y55058D01*
X850216Y55050D01*
G02X852249Y53017I-255J-2288D01*
G01X852257Y52947D01*
X861202Y44002D01*
Y35157D01*
X859122Y33077D01*
X778728D01*
X682332Y129473D01*
Y194607D01*
X679489Y197450D01*
X648011D01*
X629311Y178750D01*
X621689D01*
X611989Y188450D01*
X559589D01*
X550689Y197350D01*
X521411D01*
X502811Y178750D01*
X494689D01*
X483589Y189850D01*
X449489D01*
X442989Y196350D01*
X397411D01*
X379311Y178250D01*
X373689D01*
X361089Y190850D01*
X325189D01*
X318389Y197650D01*
X285711D01*
X266811Y178750D01*
X247189D01*
X236489Y189450D01*
X202789D01*
X196189Y196050D01*
X168611D01*
X162792Y190231D01*
X162798Y190141D01*
G02X160359Y187702I-2298J-141D01*
G01X160269Y187708D01*
X150811Y178250D01*
X120689D01*
X111189Y187750D01*
X80089D01*
X68050Y199789D01*
Y435211D01*
X214671Y581832D01*
X270969D01*
X277451Y575350D01*
X409889D01*
X438950Y604411D01*
Y610951D01*
G02Y615049I1050J2049D01*
G01Y660811D01*
X442089Y663950D01*
X489111D01*
X496750Y656311D01*
Y633311D01*
X498311Y631750D01*
X502689D01*
X534889Y663950D01*
X609611D01*
X619750Y653811D01*
Y636811D01*
X623811Y632750D01*
X629689D01*
X645642Y648703D01*
X645652Y648767D01*
G02X657926Y661041I14584J-2310D01*
G01X657990Y661051D01*
X660889Y663950D01*
X715711D01*
X721350Y658311D01*
Y183854D01*
X846146Y59058D01*
X846216Y59050D01*
G02X848249Y57017I-255J-2288D01*
G37*
G36*
G01X970474Y-46450D02*
Y-70079D01*
G02X919290I-25592J0D01*
G01Y-46456D01*
G02X960345Y-26064I25592J0D01*
G03X960986Y-25741I241J319D01*
G02X970115Y-39262I14801J151D01*
G03X969576Y-39736I-153J-369D01*
G02X970474Y-46450I-24694J-6720D01*
G37*
G36*
G01X558368Y829921D02*
G02I-55120J0D01*
G37*
G36*
G01X626340Y1095715D02*
Y1091290D01*
G02X623336I-1502J-36D01*
G01Y1095718D01*
G02X626340I1502J36D01*
G01Y1095715D01*
G37*
G36*
G01X253702D02*
Y1091290D01*
G02X250698I-1502J-36D01*
G01Y1095718D01*
G02X253702I1502J36D01*
G01Y1095715D01*
G37*
G36*
G01X129490D02*
Y1091290D01*
G02X126486I-1502J-36D01*
G01Y1095718D01*
G02X129490I1502J36D01*
G01Y1095715D01*
G37*
G36*
G01X502126D02*
Y1091293D01*
X502127Y1091290D01*
G02X499123I-1502J-36D01*
G01X499124Y1091293D01*
Y1095715D01*
X499123Y1095718D01*
G02X502127I1502J36D01*
G01X502126Y1095715D01*
G37*
G36*
G01X377914D02*
Y1091293D01*
X377915Y1091290D01*
G02X374911I-1502J-36D01*
G01X374912Y1091293D01*
Y1095715D01*
X374911Y1095718D01*
G02X377915I1502J36D01*
G01X377914Y1095715D01*
G37*
G36*
G01X253702Y642959D02*
Y638534D01*
G02X250698I-1502J-36D01*
G01Y642962D01*
G02X253702I1502J36D01*
G01Y642959D01*
G37*
G36*
G01X129490D02*
Y638534D01*
G02X126486I-1502J-36D01*
G01Y642962D01*
G02X129490I1502J36D01*
G01Y642959D01*
G37*
G36*
G01X1133310Y25749D02*
X1127311Y19750D01*
X1121089D01*
X1117089Y23750D01*
X1103311D01*
X1099411Y19850D01*
X1094889D01*
X1090750Y23989D01*
Y333611D01*
X1093289Y336150D01*
X1100011D01*
X1102911Y333250D01*
X1106389D01*
X1117689Y344550D01*
X1129131D01*
X1133310Y340371D01*
Y25749D01*
G37*
G36*
G01X1256786Y169325D02*
X1256789Y169324D01*
X1261211D01*
X1261214Y169325D01*
G02Y166321I36J-1502D01*
G01X1261211Y166322D01*
X1256789D01*
X1256786Y166321D01*
G02Y169325I-36J1502D01*
G37*
G36*
G01X1270436Y184325D02*
X1270439Y184324D01*
X1274861D01*
X1274864Y184325D01*
G02Y181321I36J-1502D01*
G01X1274861Y181322D01*
X1270439D01*
X1270436Y181321D01*
G02Y184325I-36J1502D01*
G37*
G36*
G01X1261302Y627962D02*
Y623534D01*
G02X1258298I-1502J-36D01*
G01Y627962D01*
G02X1261302I1502J36D01*
G37*
G36*
G01X1280002Y642962D02*
Y638534D01*
G02X1276998I-1502J-36D01*
G01Y642962D01*
G02X1280002I1502J36D01*
G37*
G36*
G01Y1095718D02*
Y1091290D01*
G02X1276998I-1502J-36D01*
G01Y1095718D01*
G02X1280002I1502J36D01*
G37*
G36*
G01X1069971Y1049864D02*
X1202040D01*
X1213478Y1038425D01*
Y935070D01*
X1200285Y921876D01*
X1073260D01*
X1059844Y935292D01*
Y1039737D01*
X1069971Y1049864D01*
G37*
G36*
G01X1261462Y1080754D02*
Y1076253D01*
G02X1258138Y1076254I-1662J1D01*
G01Y1080754D01*
G02X1261462I1662J0D01*
G37*
G36*
G01X1385463Y166302D02*
X1380962D01*
G02X1380963Y169344I1J1521D01*
G01X1385463D01*
G02Y166302I0J-1521D01*
G37*
G36*
G01X1404234Y190242D02*
Y185741D01*
G02X1401192Y185742I-1521J1D01*
G01Y190242D01*
G02X1404234I1521J0D01*
G37*
G36*
G01X1075250Y1416876D02*
G02Y1413872I0J-1502D01*
G01X1070749D01*
G02X1070750Y1416876I1J1502D01*
G01X1075250D01*
G37*
G36*
G01Y1409788D02*
G02Y1406786I0J-1501D01*
G01X1070749D01*
G02X1070750Y1409788I1J1501D01*
G01X1075250D01*
G37*
G36*
G01Y1402702D02*
G02Y1399700I0J-1501D01*
G01X1070749D01*
G02X1070750Y1402702I1J1501D01*
G01X1075250D01*
G37*
G36*
G01Y1395616D02*
G02Y1392612I0J-1502D01*
G01X1070749D01*
G02X1070750Y1395616I1J1502D01*
G01X1075250D01*
G37*
G36*
G01Y1388530D02*
G02Y1385526I0J-1502D01*
G01X1070749D01*
G02X1070750Y1388530I1J1502D01*
G01X1075250D01*
G37*
G36*
G01Y1381442D02*
G02Y1378440I0J-1501D01*
G01X1070749D01*
G02X1070750Y1381442I1J1501D01*
G01X1075250D01*
G37*
G36*
G01Y1303500D02*
G02Y1300476I0J-1512D01*
G01X1070749D01*
G02X1070750Y1303500I1J1512D01*
G01X1075250D01*
G37*
G36*
G01Y1310586D02*
G02Y1307564I0J-1511D01*
G01X1070749D01*
G02X1070750Y1310586I1J1511D01*
G01X1075250D01*
G37*
G36*
G01Y1317672D02*
G02Y1314650I0J-1511D01*
G01X1070749D01*
G02X1070750Y1317672I1J1511D01*
G01X1075250D01*
G37*
G36*
G01Y1324760D02*
G02Y1321736I0J-1512D01*
G01X1070749D01*
G02X1070750Y1324760I1J1512D01*
G01X1075250D01*
G37*
G36*
G01Y1331846D02*
G02Y1328824I0J-1511D01*
G01X1070749D01*
G02X1070750Y1331846I1J1511D01*
G01X1075250D01*
G37*
G36*
G01Y1296414D02*
G02Y1293390I0J-1512D01*
G01X1070749D01*
G02X1070750Y1296414I1J1512D01*
G01X1075250D01*
G37*
G36*
G01Y1211374D02*
G02Y1208350I0J-1512D01*
G01X1070749D01*
G02X1070750Y1211374I1J1512D01*
G01X1075250D01*
G37*
G36*
G01Y1218460D02*
G02Y1215438I0J-1511D01*
G01X1070749D01*
G02X1070750Y1218460I1J1511D01*
G01X1075250D01*
G37*
G36*
G01Y1225546D02*
G02Y1222524I0J-1511D01*
G01X1070749D01*
G02X1070750Y1225546I1J1511D01*
G01X1075250D01*
G37*
G36*
G01Y1232634D02*
G02Y1229610I0J-1512D01*
G01X1070749D01*
G02X1070750Y1232634I1J1512D01*
G01X1075250D01*
G37*
G36*
G01Y1239720D02*
G02Y1236698I0J-1511D01*
G01X1070749D01*
G02X1070750Y1239720I1J1511D01*
G01X1075250D01*
G37*
G36*
G01Y1246806D02*
G02Y1243784I0J-1511D01*
G01X1070749D01*
G02X1070750Y1246806I1J1511D01*
G01X1075250D01*
G37*
G36*
G01X1124313Y534842D02*
X1124318Y534833D01*
X1116440Y530894D01*
X1116437Y530899D01*
X1116339Y530857D01*
G02X1113786Y535977I-1183J2607D01*
G01X1113872Y536027D01*
X1113870Y536032D01*
X1121747Y539971D01*
X1121753Y539965D01*
X1121814Y539992D01*
G02X1124313Y534842I1217J-2591D01*
G37*
G36*
G01X1113922Y693414D02*
X1121763Y697334D01*
X1121764Y697335D01*
G02X1124266Y692411I1267J-2454D01*
G01X1116392Y688474D01*
G02X1113922Y693414I-1235J2470D01*
G37*
G36*
G01Y677666D02*
X1121763Y681586D01*
X1121764Y681587D01*
G02X1124266Y676663I1267J-2454D01*
G01X1116392Y672726D01*
G02X1113922Y677666I-1235J2470D01*
G37*
G36*
G01Y709162D02*
X1121763Y713082D01*
X1121764Y713083D01*
G02X1124266Y708159I1267J-2454D01*
G01X1116392Y704222D01*
G02X1113922Y709162I-1235J2470D01*
G37*
G36*
G01Y661918D02*
X1121763Y665838D01*
X1121764Y665839D01*
G02X1124266Y660915I1267J-2454D01*
G01X1116392Y656978D01*
G02X1113922Y661918I-1235J2470D01*
G37*
G36*
G01Y646170D02*
X1121763Y650090D01*
X1121764Y650091D01*
G02X1124266Y645167I1267J-2454D01*
G01X1116392Y641230D01*
G02X1113922Y646170I-1235J2470D01*
G37*
G36*
G01X1124266Y629419D02*
X1116425Y625499D01*
X1116424Y625498D01*
G02X1113922Y630422I-1267J2454D01*
G01X1121796Y634359D01*
G02X1124266Y629419I1235J-2470D01*
G37*
G36*
G01X1113922Y614674D02*
X1121763Y618594D01*
X1121764Y618595D01*
G02X1124266Y613671I1267J-2454D01*
G01X1116392Y609734D01*
G02X1113922Y614674I-1235J2470D01*
G37*
G36*
G01Y598926D02*
X1121763Y602846D01*
X1121764Y602847D01*
G02X1124266Y597923I1267J-2454D01*
G01X1116392Y593986D01*
G02X1113922Y598926I-1235J2470D01*
G37*
G36*
G01Y504438D02*
X1121763Y508358D01*
X1121764Y508359D01*
G02X1124266Y503435I1267J-2454D01*
G01X1116392Y499498D01*
G02X1113922Y504438I-1235J2470D01*
G37*
G36*
G01Y488690D02*
X1121763Y492610D01*
X1121764Y492611D01*
G02X1124266Y487687I1267J-2454D01*
G01X1116392Y483750D01*
G02X1113922Y488690I-1235J2470D01*
G37*
G36*
G01Y472942D02*
X1121763Y476862D01*
X1121764Y476863D01*
G02X1124266Y471939I1267J-2454D01*
G01X1116392Y468002D01*
G02X1113922Y472942I-1235J2470D01*
G37*
G36*
G01Y457194D02*
X1121763Y461114D01*
X1121764Y461115D01*
G02X1124266Y456191I1267J-2454D01*
G01X1116392Y452254D01*
G02X1113922Y457194I-1235J2470D01*
G37*
G36*
G01X1113872Y425796D02*
X1121746Y429733D01*
G02X1124316Y424597I1285J-2568D01*
G01X1116442Y420660D01*
G02X1113872Y425796I-1285J2568D01*
G37*
G36*
G01X1104199Y696183D02*
X1104034Y696253D01*
X1104032Y696249D01*
X1096156Y700187D01*
Y700195D01*
X1096053Y700252D01*
G02X1098557Y705390I1388J2503D01*
G01X1098722Y705320D01*
X1098724Y705324D01*
X1106601Y701386D01*
X1106599Y701382D01*
X1106767Y701283D01*
G02X1104199Y696183I-1453J-2465D01*
G37*
G36*
G01Y680435D02*
X1104034Y680505D01*
X1104032Y680501D01*
X1096156Y684439D01*
Y684447D01*
X1096053Y684504D01*
G02X1098557Y689642I1388J2503D01*
G01X1098722Y689572D01*
X1098724Y689576D01*
X1106601Y685638D01*
X1106599Y685634D01*
X1106767Y685535D01*
G02X1104199Y680435I-1453J-2465D01*
G37*
G36*
G01Y664687D02*
X1104034Y664757D01*
X1104032Y664753D01*
X1096156Y668691D01*
Y668699D01*
X1096053Y668756D01*
G02X1098557Y673894I1388J2503D01*
G01X1098722Y673824D01*
X1098724Y673828D01*
X1106601Y669890D01*
X1106599Y669886D01*
X1106767Y669787D01*
G02X1104199Y664687I-1453J-2465D01*
G37*
G36*
G01Y648939D02*
X1104034Y649009D01*
X1104032Y649005D01*
X1096156Y652943D01*
Y652951D01*
X1096053Y653008D01*
G02X1098557Y658146I1388J2503D01*
G01X1098722Y658076D01*
X1098724Y658080D01*
X1106601Y654142D01*
X1106599Y654138D01*
X1106767Y654039D01*
G02X1104199Y648939I-1453J-2465D01*
G37*
G36*
G01X1104039Y617528D02*
X1096133Y621481D01*
X1096062Y621519D01*
G02X1098717Y626565I1379J2496D01*
G01X1106591Y622628D01*
G02X1104039Y617528I-1276J-2550D01*
G37*
G36*
G01Y633276D02*
X1096133Y637229D01*
X1096062Y637267D01*
G02X1098717Y642313I1379J2496D01*
G01X1106591Y638376D01*
G02X1104039Y633276I-1276J-2550D01*
G37*
G36*
G01Y586032D02*
X1096133Y589985D01*
X1096062Y590023D01*
G02X1098717Y595069I1379J2496D01*
G01X1106591Y591132D01*
G02X1104039Y586032I-1276J-2550D01*
G37*
G36*
G01Y601780D02*
X1096133Y605733D01*
X1096062Y605771D01*
G02X1098717Y610817I1379J2496D01*
G01X1106591Y606880D01*
G02X1104039Y601780I-1276J-2550D01*
G37*
G36*
G01X1104199Y538703D02*
X1104034Y538773D01*
X1104032Y538769D01*
X1096156Y542707D01*
Y542715D01*
X1096053Y542772D01*
G02X1098557Y547910I1388J2503D01*
G01X1098722Y547840D01*
X1098724Y547844D01*
X1106601Y543906D01*
X1106599Y543902D01*
X1106767Y543803D01*
G02X1104199Y538703I-1453J-2465D01*
G37*
G36*
G01X1104039Y475796D02*
X1096133Y479749D01*
X1096062Y479787D01*
G02X1098717Y484833I1379J2496D01*
G01X1106591Y480896D01*
G02X1104039Y475796I-1276J-2550D01*
G37*
G36*
G01Y491544D02*
X1096133Y495497D01*
X1096062Y495535D01*
G02X1098717Y500581I1379J2496D01*
G01X1106591Y496644D01*
G02X1104039Y491544I-1276J-2550D01*
G37*
G36*
G01Y507292D02*
X1096133Y511245D01*
X1096062Y511283D01*
G02X1098717Y516329I1379J2496D01*
G01X1106591Y512392D01*
G02X1104039Y507292I-1276J-2550D01*
G37*
G36*
G01X1098676Y453257D02*
X1106550Y449320D01*
G02X1104080Y444380I-1235J-2470D01*
G01X1096239Y448301D01*
X1096238D01*
G02X1098676Y453257I1203J2486D01*
G37*
G36*
G01X1104039Y460048D02*
X1096133Y464001D01*
X1096062Y464039D01*
G02X1098717Y469085I1379J2496D01*
G01X1106591Y465148D01*
G02X1104039Y460048I-1276J-2550D01*
G37*
G36*
G01X1535036Y91930D02*
Y86417D01*
G02X1530712Y86418I-2162J1D01*
G01Y91930D01*
G02X1535036I2162J0D01*
G37*
G36*
G01X1520862D02*
Y86417D01*
G02X1516540Y86418I-2161J1D01*
G01Y91930D01*
G02X1520862I2161J0D01*
G37*
G36*
G01X1506690D02*
Y86417D01*
G02X1502366Y86418I-2162J1D01*
G01Y91930D01*
G02X1506690I2162J0D01*
G37*
G36*
G01X1506700Y120276D02*
Y114763D01*
G02X1502356Y114764I-2172J1D01*
G01Y120276D01*
G02X1506700I2172J0D01*
G37*
G36*
G01X1535036D02*
Y114763D01*
G02X1530712Y114764I-2162J1D01*
G01Y120276D01*
G02X1535036I2162J0D01*
G37*
G36*
G01Y77756D02*
Y72244D01*
G02X1530712Y72245I-2162J1D01*
G01Y77756D01*
G02X1535036I2162J0D01*
G37*
G36*
G01X1520862D02*
Y72244D01*
G02X1516540Y72245I-2161J1D01*
G01Y77756D01*
G02X1520862I2161J0D01*
G37*
G36*
G01X1506690D02*
Y72244D01*
G02X1502366Y72245I-2162J1D01*
G01Y77756D01*
G02X1506690I2162J0D01*
G37*
G36*
G01X1527948Y87993D02*
Y82480D01*
G02X1523626Y82481I-2161J1D01*
G01Y87993D01*
G02X1527948I2161J0D01*
G37*
G36*
G01X1513776D02*
Y82480D01*
G02X1509452Y82481I-2162J1D01*
G01Y87993D01*
G02X1513776I2162J0D01*
G37*
G36*
G01X1499602D02*
Y82480D01*
G02X1495280Y82481I-2161J1D01*
G01Y87993D01*
G02X1499602I2161J0D01*
G37*
G36*
G01X1449996Y91930D02*
Y86417D01*
G02X1445674Y86418I-2161J1D01*
G01Y91930D01*
G02X1449996I2161J0D01*
G37*
G36*
G01X1445664Y114764D02*
Y120277D01*
G02X1450006Y120276I2171J-1D01*
G01Y114764D01*
G02X1445664I-2171J0D01*
G37*
G36*
G01X1492516Y77756D02*
Y72244D01*
G02X1488192Y72245I-2162J1D01*
G01Y77756D01*
G02X1492516I2162J0D01*
G37*
G36*
G01X1449996D02*
Y72244D01*
G02X1445674Y72245I-2161J1D01*
G01Y77756D01*
G02X1449996I2161J0D01*
G37*
G36*
G01X1435822Y91930D02*
Y86417D01*
G02X1431500Y86418I-2161J1D01*
G01Y91930D01*
G02X1435822I2161J0D01*
G37*
G36*
G01X1421650D02*
Y86417D01*
G02X1417326Y86418I-2162J1D01*
G01Y91930D01*
G02X1421650I2162J0D01*
G37*
G36*
G01X1407476D02*
Y86417D01*
G02X1403154Y86418I-2161J1D01*
G01Y91930D01*
G02X1407476I2161J0D01*
G37*
G36*
G01X1428736Y116339D02*
Y110826D01*
G02X1424414Y110827I-2161J1D01*
G01Y116339D01*
G02X1428736I2161J0D01*
G37*
G36*
G01X1435822Y77756D02*
Y72244D01*
G02X1431500Y72245I-2161J1D01*
G01Y77756D01*
G02X1435822I2161J0D01*
G37*
G36*
G01X1421650D02*
Y72244D01*
G02X1417326Y72245I-2162J1D01*
G01Y77756D01*
G02X1421650I2162J0D01*
G37*
G36*
G01X1407476D02*
Y72244D01*
G02X1403154Y72245I-2161J1D01*
G01Y77756D01*
G02X1407476I2161J0D01*
G37*
G36*
G01X1442910Y87993D02*
Y82480D01*
G02X1438586Y82481I-2162J1D01*
G01Y87993D01*
G02X1442910I2162J0D01*
G37*
G36*
G01X1428736D02*
Y82480D01*
G02X1424414Y82481I-2161J1D01*
G01Y87993D01*
G02X1428736I2161J0D01*
G37*
G36*
G01X1414564D02*
Y82480D01*
G02X1410240Y82481I-2162J1D01*
G01Y87993D01*
G02X1414564I2162J0D01*
G37*
G36*
G01X1400390D02*
Y82480D01*
G02X1396066Y82481I-2162J1D01*
G01Y87993D01*
G02X1400390I2162J0D01*
G37*
G36*
G01X1898061Y1091290D02*
X1898062Y1091293D01*
Y1095715D01*
X1898061Y1095718D01*
G02X1901065I1502J36D01*
G01X1901064Y1095715D01*
Y1091293D01*
X1901065Y1091290D01*
G02X1898061I-1502J-36D01*
G37*
G36*
G01X1652640Y642962D02*
Y638534D01*
G02X1649636I-1502J-36D01*
G01Y642962D01*
G02X1652640I1502J36D01*
G37*
G36*
G01X1401211Y638534D02*
X1401212Y638537D01*
Y642959D01*
X1401211Y642962D01*
G02X1404215I1502J36D01*
G01X1404214Y642959D01*
Y638537D01*
X1404215Y638534D01*
G02X1401211I-1502J-36D01*
G37*
G36*
G01X1633940Y627962D02*
Y623534D01*
G02X1630936I-1502J-36D01*
G01Y627962D01*
G02X1633940I1502J36D01*
G37*
G36*
G01X1506723Y623534D02*
X1506724Y623537D01*
Y627959D01*
X1506723Y627962D01*
G02X1509727I1502J36D01*
G01X1509726Y627959D01*
Y623537D01*
X1509727Y623534D01*
G02X1506723I-1502J-36D01*
G37*
G36*
G01X1382511D02*
X1382512Y623537D01*
Y627959D01*
X1382511Y627962D01*
G02X1385515I1502J36D01*
G01X1385514Y627959D01*
Y623537D01*
X1385515Y623534D01*
G02X1382511I-1502J-36D01*
G37*
G36*
G01X1898061Y185778D02*
X1898062Y185781D01*
Y190203D01*
X1898061Y190206D01*
G02X1901065I1502J36D01*
G01X1901064Y190203D01*
Y185781D01*
X1901065Y185778D01*
G02X1898061I-1502J-36D01*
G37*
G36*
G01X1525423D02*
X1525424Y185781D01*
Y190203D01*
X1525423Y190206D01*
G02X1528427I1502J36D01*
G01X1528426Y190203D01*
Y185781D01*
X1528427Y185778D01*
G02X1525423I-1502J-36D01*
G37*
G36*
G01X1511414Y180198D02*
X1506986D01*
G02Y183202I-36J1502D01*
G01X1511414D01*
G02Y180198I36J-1502D01*
G37*
G36*
G01X1879361Y170778D02*
X1879362Y170781D01*
Y175203D01*
X1879361Y175206D01*
G02X1882365I1502J36D01*
G01X1882364Y175203D01*
Y170781D01*
X1882365Y170778D01*
G02X1879361I-1502J-36D01*
G37*
G36*
G01X1729038Y829921D02*
G02I-55121J0D01*
G37*
G36*
G01X1776852Y1095715D02*
Y1091290D01*
G02X1773848I-1502J-36D01*
G01Y1095718D01*
G02X1776852I1502J36D01*
G01Y1095715D01*
G37*
G36*
G01X1652640D02*
Y1091290D01*
G02X1649636I-1502J-36D01*
G01Y1095718D01*
G02X1652640I1502J36D01*
G01Y1095715D01*
G37*
G36*
G01X1528426D02*
Y1091293D01*
X1528427Y1091290D01*
G02X1525423I-1502J-36D01*
G01X1525424Y1091293D01*
Y1095715D01*
X1525423Y1095718D01*
G02X1528427I1502J36D01*
G01X1528426Y1095715D01*
G37*
G36*
G01X1404214D02*
Y1091293D01*
X1404215Y1091290D01*
G02X1401211I-1502J-36D01*
G01X1401212Y1091293D01*
Y1095715D01*
X1401211Y1095718D01*
G02X1404215I1502J36D01*
G01X1404214Y1095715D01*
G37*
G36*
G01X1882364Y1080715D02*
Y1076293D01*
X1882365Y1076290D01*
G02X1879361I-1502J-36D01*
G01X1879362Y1076293D01*
Y1080715D01*
X1879361Y1080718D01*
G02X1882365I1502J36D01*
G01X1882364Y1080715D01*
G37*
G36*
G01X1758152D02*
Y1076290D01*
G02X1755148I-1502J-36D01*
G01Y1080718D01*
G02X1758152I1502J36D01*
G01Y1080715D01*
G37*
G36*
G01X1633940D02*
Y1076290D01*
G02X1630936I-1502J-36D01*
G01Y1080718D01*
G02X1633940I1502J36D01*
G01Y1080715D01*
G37*
G36*
G01X1509726D02*
Y1076293D01*
X1509727Y1076290D01*
G02X1506723I-1502J-36D01*
G01X1506724Y1076293D01*
Y1080715D01*
X1506723Y1080718D01*
G02X1509727I1502J36D01*
G01X1509726Y1080715D01*
G37*
G36*
G01X1385514D02*
Y1076293D01*
X1385515Y1076290D01*
G02X1382511I-1502J-36D01*
G01X1382512Y1076293D01*
Y1080715D01*
X1382511Y1080718D01*
G02X1385515I1502J36D01*
G01X1385514Y1080715D01*
G37*
G36*
G01X1897508Y459879D02*
G02X1891860I-2824J10580D01*
G02Y488939I2824J14530D01*
G02X1897508I2824J-10580D01*
G02Y459879I-2824J-14530D01*
G37*
G36*
G01X1898061Y638534D02*
X1898062Y638537D01*
Y642959D01*
X1898061Y642962D01*
G02X1901065I1502J36D01*
G01X1901064Y642959D01*
Y638537D01*
X1901065Y638534D01*
G02X1898061I-1502J-36D01*
G37*
G36*
G01X1726852Y642962D02*
Y638534D01*
G02X1723848I-1502J-36D01*
G01Y642962D01*
G02X1726852I1502J36D01*
G37*
G36*
G01X1879361Y623534D02*
X1879362Y623537D01*
Y627959D01*
X1879361Y627962D01*
G02X1882365I1502J36D01*
G01X1882364Y627959D01*
Y623537D01*
X1882365Y623534D01*
G02X1879361I-1502J-36D01*
G37*
G36*
G01X1733152Y627962D02*
Y623534D01*
G02X1730148I-1502J-36D01*
G01Y627962D01*
G02X1733152I1502J36D01*
G37*
G36*
G01X1776852Y190206D02*
Y185778D01*
G02X1773848I-1502J-36D01*
G01Y190206D01*
G02X1776852I1502J36D01*
G37*
G36*
G01X1652640D02*
Y185778D01*
G02X1649636I-1502J-36D01*
G01Y190206D01*
G02X1652640I1502J36D01*
G37*
G36*
G01X1758152Y175206D02*
Y170778D01*
G02X1755148I-1502J-36D01*
G01Y175206D01*
G02X1758152I1502J36D01*
G37*
G36*
G01X1633940D02*
Y170778D01*
G02X1630936I-1502J-36D01*
G01Y175206D01*
G02X1633940I1502J36D01*
G37*
G54D53*
X111024Y153681D03*
Y606437D03*
X235236Y153681D03*
Y606437D03*
X359449Y153681D03*
Y606437D03*
X483661Y153681D03*
X607874D03*
X732087Y606437D03*
Y1059193D03*
X949902Y-115157D03*
X111024Y1059193D03*
X235236D03*
X359449D03*
X483661D03*
X607874D03*
X1405906Y153681D03*
X1281693Y1059193D03*
Y606437D03*
Y153681D03*
X1405906Y606437D03*
X1530118Y153681D03*
Y606437D03*
X1654331Y153681D03*
Y606437D03*
X1778543Y153681D03*
X1902756D03*
Y1059193D03*
X1405906D03*
X1530118D03*
X1654331D03*
X1778543D03*
Y606437D03*
X1902756D03*
G54D55*
X359449Y755059D03*
X483661D03*
X607874D03*
X732087Y302303D03*
Y755059D03*
X111024Y1207815D03*
X235236D03*
X359449D03*
X483661D03*
X607874D03*
X732087D03*
X111024Y755059D03*
X235236D03*
X1098524Y-115157D03*
X1281693Y755059D03*
Y302303D03*
Y1207815D03*
X1405906Y302303D03*
Y1207815D03*
X1530118Y302303D03*
Y1207815D03*
X1654331Y755059D03*
Y1207815D03*
X1778543D03*
X1902756Y302303D03*
Y1207815D03*
X1405906Y755059D03*
X1530118D03*
X1654331Y302303D03*
X1778543D03*
Y755059D03*
X1902756D03*
G54D54*
X79000Y1301900D03*
X1826700Y77600D03*
X1908500Y1346800D03*
G54D52*
X80019Y51968D03*
X127263Y20472D03*
X631200Y51968D03*
X678444Y20472D03*
X1250689Y51969D03*
X1297933Y20472D03*
X1801870Y51969D03*
X1849114Y20472D03*
G54D60*
X670079Y1114173D03*
X1343700D03*
X1840551D03*
G54D58*
X942126Y58465D03*
Y346457D03*
Y437598D03*
Y725590D03*
X1110236Y346457D03*
Y437598D03*
Y725590D03*
G54D57*
X496653Y80906D03*
X1465157D03*
G54D51*
X103642Y36220D03*
X654822D03*
X173228Y1062992D03*
X670079D03*
X1274311Y36220D03*
X1592126Y1141732D03*
X1825492Y36220D03*
X1343701Y1062992D03*
X1840551D03*
G54D50*
X31496Y882677D03*
X718110Y820866D03*
X904921Y564961D03*
X1894685Y21654D03*
X1462992Y866929D03*
G54D59*
X975788Y564961D03*
G54D56*
X496654Y110551D03*
G54D48*
X796457Y735444D03*
Y263003D03*
X627263Y829910D03*
X131201Y1282666D03*
X1797933D03*
X1549901D03*
Y377154D03*
Y829910D03*
X1797933Y377154D03*
G54D64*
X1130459Y1351595D03*
X1126522Y1330335D03*
Y1259469D03*
X1130459Y1280729D03*
X1126522Y1188603D03*
X1102113Y1394115D03*
X1098176Y1401201D03*
X1102113Y1351595D03*
X1098176Y1372855D03*
Y1330335D03*
Y1301989D03*
X1102113Y1309075D03*
Y1323249D03*
Y1280729D03*
X1098176Y1259469D03*
X1102113Y1209863D03*
X1098176Y1216949D03*
Y1231123D03*
X1102113Y1238209D03*
Y1167343D03*
X1098176Y1160257D03*
Y1188603D03*
G54D49*
X379232Y1282666D03*
Y829910D03*
X131200D03*
X961418Y1429932D03*
Y1087413D03*
X1181890Y555917D03*
X1301870Y377154D03*
Y829910D03*
X1181890Y1559854D03*
X1301870Y1282666D03*
G54D63*
X1126522Y1344508D03*
Y1358682D03*
X1130459Y1365768D03*
Y1337422D03*
Y1252382D03*
Y1266556D03*
X1126522Y1273642D03*
Y1245296D03*
Y1174430D03*
X1130459Y1181516D03*
Y1195690D03*
X1102113Y1408288D03*
Y1365768D03*
X1098176Y1358682D03*
Y1344508D03*
X1102113Y1379942D03*
X1098176Y1387028D03*
X1102113Y1337422D03*
X1098176Y1316162D03*
Y1273642D03*
X1102113Y1266556D03*
Y1252382D03*
X1098176Y1287816D03*
X1102113Y1294902D03*
X1098176Y1245296D03*
Y1202776D03*
X1102113Y1224036D03*
Y1195690D03*
Y1181516D03*
X1098176Y1174430D03*
G54D62*
X1126522Y1401201D03*
X1130459Y1394115D03*
X1126522Y1372855D03*
X1130459Y1323249D03*
Y1309075D03*
X1126522Y1301989D03*
X1130459Y1238209D03*
X1126522Y1231123D03*
Y1216949D03*
X1130459Y1209863D03*
Y1167343D03*
X1126522Y1160257D03*
G54D61*
X1130459Y1408288D03*
X1126522Y1387028D03*
X1130459Y1379942D03*
X1126522Y1316162D03*
X1130459Y1294902D03*
X1126522Y1287816D03*
X1130459Y1224036D03*
X1126522Y1202776D03*
%LPC*%
G75*
G36*
G01X167989Y197550D02*
X162102Y191663D01*
X161962Y191778D01*
G03X158842Y188403I-1462J-1778D01*
G01X150189Y179750D01*
X121311D01*
X111811Y189250D01*
X80711D01*
X69550Y200411D01*
Y434589D01*
X215293Y580332D01*
X270347D01*
X276829Y573850D01*
X410511D01*
X440450Y603789D01*
Y610737D01*
X440598Y610777D01*
G03Y615223I-598J2223D01*
G01X440450Y615263D01*
Y660189D01*
X442711Y662450D01*
X488489D01*
X495250Y655689D01*
Y632689D01*
X497689Y630250D01*
X503311D01*
X535511Y662450D01*
X608989D01*
X618250Y653189D01*
Y636189D01*
X623189Y631250D01*
X630311D01*
X644819Y645758D01*
G02X645501Y645502I283J-282D01*
G03X661191Y661192I14735J955D01*
G02X660935Y661874I26J399D01*
G01X661511Y662450D01*
X715089D01*
X719850Y657689D01*
Y464105D01*
G03Y460895I1650J-1605D01*
G01Y183232D01*
X859702Y43380D01*
Y35779D01*
X858500Y34577D01*
X779350D01*
X683832Y130095D01*
Y195229D01*
X680111Y198950D01*
X647389D01*
X628689Y180250D01*
X622311D01*
X612611Y189950D01*
X568922D01*
X568912Y189951D01*
G03X568462I-225J-2291D01*
G01X568452Y189950D01*
X560211D01*
X551311Y198850D01*
X520789D01*
X502189Y180250D01*
X498409D01*
X498383Y180257D01*
G03X497187I-598J-2223D01*
G01X497161Y180250D01*
X495311D01*
X484211Y191350D01*
X450111D01*
X443611Y197850D01*
X396789D01*
X378689Y179750D01*
X374311D01*
X361711Y192350D01*
X325811D01*
X319011Y199150D01*
X285089D01*
X266189Y180250D01*
X247811D01*
X237111Y190950D01*
X203411D01*
X196811Y197550D01*
X167989D01*
G37*
G36*
G01X1074917Y925878D02*
X1063846Y936949D01*
Y1038080D01*
X1071628Y1045862D01*
X1200383D01*
X1209477Y1036768D01*
Y987703D01*
G02X1208688Y987608I-400J-1D01*
G03X1154268Y981080I-26818J-6528D01*
G01Y957480D01*
G03X1208688Y950952I27602J0D01*
G02X1209477Y950857I389J-94D01*
G01Y936727D01*
X1198628Y925878D01*
X1074917D01*
G37*
G36*
G01X1121711Y21250D02*
X1117711Y25250D01*
X1102689D01*
X1098789Y21350D01*
X1095511D01*
X1092250Y24611D01*
Y332989D01*
X1093911Y334650D01*
X1099389D01*
X1102289Y331750D01*
X1107011D01*
X1118311Y343050D01*
X1128509D01*
X1131810Y339749D01*
Y176592D01*
G03Y176408I2300J-92D01*
G01Y26371D01*
X1126689Y21250D01*
X1121711D01*
G37*
%LPD*%
G75*
G36*
G01X626340Y190203D02*
Y185778D01*
G02X623336I-1502J-36D01*
G01Y190206D01*
G02X626340I1502J36D01*
G01Y190203D01*
G37*
G36*
G01X502126D02*
Y185781D01*
X502127Y185778D01*
G02X499123I-1502J-36D01*
G01X499124Y185781D01*
Y190203D01*
X499123Y190206D01*
G02X502127I1502J36D01*
G01X502126Y190203D01*
G37*
G36*
G01X377914D02*
Y185781D01*
X377915Y185778D01*
G02X374911I-1502J-36D01*
G01X374912Y185781D01*
Y190203D01*
X374911Y190206D01*
G02X377915I1502J36D01*
G01X377914Y190203D01*
G37*
G36*
G01X253702D02*
Y185778D01*
G02X250698I-1502J-36D01*
G01Y190206D01*
G02X253702I1502J36D01*
G01Y190203D01*
G37*
G36*
G01X129490D02*
Y185778D01*
G02X126486I-1502J-36D01*
G01Y190206D01*
G02X129490I1502J36D01*
G01Y190203D01*
G37*
G36*
G01X1116392Y277845D02*
G02X1113922Y282785I-1235J2470D01*
G01X1121763Y286705D01*
X1121764Y286706D01*
G02X1124266Y281782I1267J-2454D01*
G01X1116392Y277845D01*
G37*
G36*
G01Y325089D02*
G02X1113922Y330029I-1235J2470D01*
G01X1121763Y333949D01*
X1121764Y333950D01*
G02X1124266Y329026I1267J-2454D01*
G01X1116392Y325089D01*
G37*
G36*
G01Y309341D02*
G02X1113922Y314281I-1235J2470D01*
G01X1121763Y318201D01*
X1121764Y318202D01*
G02X1124266Y313278I1267J-2454D01*
G01X1116392Y309341D01*
G37*
G36*
G01Y293593D02*
G02X1113922Y298533I-1235J2470D01*
G01X1121763Y302453D01*
X1121764Y302454D01*
G02X1124266Y297530I1267J-2454D01*
G01X1116392Y293593D01*
G37*
G36*
G01Y230601D02*
G02X1113922Y235541I-1235J2470D01*
G01X1121763Y239461D01*
X1121764Y239462D01*
G02X1124266Y234538I1267J-2454D01*
G01X1116392Y230601D01*
G37*
G36*
G01Y262097D02*
G02X1113922Y267037I-1235J2470D01*
G01X1121763Y270957D01*
X1121764Y270958D01*
G02X1124266Y266034I1267J-2454D01*
G01X1116392Y262097D01*
G37*
G36*
G01Y246349D02*
G02X1113922Y251289I-1235J2470D01*
G01X1121763Y255209D01*
X1121764Y255210D01*
G02X1124266Y250286I1267J-2454D01*
G01X1116392Y246349D01*
G37*
G36*
G01Y183357D02*
G02X1113922Y188297I-1235J2470D01*
G01X1121763Y192217D01*
X1121764Y192218D01*
G02X1124266Y187294I1267J-2454D01*
G01X1116392Y183357D01*
G37*
G36*
G01Y214853D02*
G02X1113922Y219793I-1235J2470D01*
G01X1121763Y223713D01*
X1121764Y223714D01*
G02X1124266Y218790I1267J-2454D01*
G01X1116392Y214853D01*
G37*
G36*
G01Y199105D02*
G02X1113922Y204045I-1235J2470D01*
G01X1121763Y207965D01*
X1121764Y207966D01*
G02X1124266Y203042I1267J-2454D01*
G01X1116392Y199105D01*
G37*
G36*
G01X1121741Y145097D02*
G02X1124320Y139943I1290J-2577D01*
G01X1116446Y136006D01*
G02X1113868Y141160I-1289J2577D01*
G01X1121741Y145097D01*
G37*
G36*
G01X1116392Y167609D02*
G02X1113922Y172549I-1235J2470D01*
G01X1121763Y176469D01*
X1121764Y176470D01*
G02X1124266Y171546I1267J-2454D01*
G01X1116392Y167609D01*
G37*
G36*
G01Y151861D02*
G02X1113922Y156801I-1235J2470D01*
G01X1121763Y160721D01*
X1121764Y160722D01*
G02X1124266Y155798I1267J-2454D01*
G01X1116392Y151861D01*
G37*
G36*
G01X1104199Y301302D02*
X1104034Y301372D01*
X1104032Y301368D01*
X1096156Y305306D01*
Y305314D01*
X1096053Y305371D01*
G02X1098557Y310509I1388J2503D01*
G01X1098722Y310439D01*
X1098724Y310443D01*
X1106601Y306505D01*
X1106599Y306501D01*
X1106767Y306402D01*
G02X1104199Y301302I-1453J-2465D01*
G37*
G36*
G01Y285554D02*
X1104034Y285624D01*
X1104032Y285620D01*
X1096156Y289558D01*
Y289566D01*
X1096053Y289623D01*
G02X1098557Y294761I1388J2503D01*
G01X1098722Y294691D01*
X1098724Y294695D01*
X1106601Y290757D01*
X1106599Y290753D01*
X1106767Y290654D01*
G02X1104199Y285554I-1453J-2465D01*
G37*
G36*
G01Y317050D02*
X1104034Y317120D01*
X1104032Y317116D01*
X1096156Y321054D01*
Y321062D01*
X1096053Y321119D01*
G02X1098557Y326257I1388J2503D01*
G01X1098722Y326187D01*
X1098724Y326191D01*
X1106601Y322253D01*
X1106599Y322249D01*
X1106767Y322150D01*
G02X1104199Y317050I-1453J-2465D01*
G37*
G36*
G01Y254058D02*
X1104034Y254128D01*
X1104032Y254124D01*
X1096156Y258062D01*
Y258070D01*
X1096053Y258127D01*
G02X1098557Y263265I1388J2503D01*
G01X1098722Y263195D01*
X1098724Y263199D01*
X1106601Y259261D01*
X1106599Y259257D01*
X1106767Y259158D01*
G02X1104199Y254058I-1453J-2465D01*
G37*
G36*
G01Y238310D02*
X1104034Y238380D01*
X1104032Y238376D01*
X1096156Y242314D01*
Y242322D01*
X1096053Y242379D01*
G02X1098557Y247517I1388J2503D01*
G01X1098722Y247447D01*
X1098724Y247451D01*
X1106601Y243513D01*
X1106599Y243509D01*
X1106767Y243410D01*
G02X1104199Y238310I-1453J-2465D01*
G37*
G36*
G01Y269806D02*
X1104034Y269876D01*
X1104032Y269872D01*
X1096156Y273810D01*
Y273818D01*
X1096053Y273875D01*
G02X1098557Y279013I1388J2503D01*
G01X1098722Y278943D01*
X1098724Y278947D01*
X1106601Y275009D01*
X1106599Y275005D01*
X1106767Y274906D01*
G02X1104199Y269806I-1453J-2465D01*
G37*
G36*
G01Y206814D02*
X1104034Y206884D01*
X1104032Y206880D01*
X1096156Y210818D01*
Y210826D01*
X1096053Y210883D01*
G02X1098557Y216021I1388J2503D01*
G01X1098722Y215951D01*
X1098724Y215955D01*
X1106601Y212017D01*
X1106599Y212013D01*
X1106767Y211914D01*
G02X1104199Y206814I-1453J-2465D01*
G37*
G36*
G01Y191066D02*
X1104034Y191136D01*
X1104032Y191132D01*
X1096156Y195070D01*
Y195078D01*
X1096053Y195135D01*
G02X1098557Y200273I1388J2503D01*
G01X1098722Y200203D01*
X1098724Y200207D01*
X1106601Y196269D01*
X1106599Y196265D01*
X1106767Y196166D01*
G02X1104199Y191066I-1453J-2465D01*
G37*
G36*
G01Y222562D02*
X1104034Y222632D01*
X1104032Y222628D01*
X1096156Y226566D01*
Y226574D01*
X1096053Y226631D01*
G02X1098557Y231769I1388J2503D01*
G01X1098722Y231699D01*
X1098724Y231703D01*
X1106601Y227765D01*
X1106599Y227761D01*
X1106767Y227662D01*
G02X1104199Y222562I-1453J-2465D01*
G37*
G36*
G01Y143822D02*
X1104034Y143892D01*
X1104032Y143888D01*
X1096156Y147826D01*
Y147834D01*
X1096053Y147891D01*
G02X1098557Y153029I1388J2503D01*
G01X1098722Y152959D01*
X1098724Y152963D01*
X1106601Y149025D01*
X1106599Y149021D01*
X1106767Y148922D01*
G02X1104199Y143822I-1453J-2465D01*
G37*
G36*
G01Y175318D02*
X1104034Y175388D01*
X1104032Y175384D01*
X1096156Y179322D01*
Y179330D01*
X1096053Y179387D01*
G02X1098557Y184525I1388J2503D01*
G01X1098722Y184455D01*
X1098724Y184459D01*
X1106601Y180521D01*
X1106599Y180517D01*
X1106767Y180418D01*
G02X1104199Y175318I-1453J-2465D01*
G37*
G36*
G01Y159570D02*
X1104034Y159640D01*
X1104032Y159636D01*
X1096156Y163574D01*
Y163582D01*
X1096053Y163639D01*
G02X1098557Y168777I1388J2503D01*
G01X1098722Y168707D01*
X1098724Y168711D01*
X1106601Y164773D01*
X1106599Y164769D01*
X1106767Y164670D01*
G02X1104199Y159570I-1453J-2465D01*
G37*
G36*
G01X1096194Y45434D02*
G02X1098730Y50609I1248J2597D01*
G01X1106604Y46672D01*
G02X1104026Y41518I-1289J-2577D01*
G01X1096195Y45434D01*
X1096194D01*
G37*
G36*
G01X1104199Y65082D02*
X1104034Y65152D01*
X1104032Y65148D01*
X1096156Y69086D01*
Y69094D01*
X1096053Y69151D01*
G02X1098557Y74289I1388J2503D01*
G01X1098722Y74219D01*
X1098724Y74223D01*
X1106601Y70285D01*
X1106599Y70281D01*
X1106767Y70182D01*
G02X1104199Y65082I-1453J-2465D01*
G37*
G54D53*
X483661Y606437D03*
X607874D03*
X732087Y153681D03*
G54D55*
X111024Y302303D03*
X235236D03*
X359449D03*
X483661D03*
X607874D03*
G54D58*
X1110236Y58465D03*
G54D48*
X627263Y377154D03*
X131201D03*
G54D49*
X379232D03*
G54D63*
X1116286Y1038198D03*
G54D62*
X1126522Y1031111D03*
X1130459Y1024025D03*
X1126522Y1002765D03*
X1102113Y1024025D03*
X1098176Y1031111D03*
Y1002765D03*
G54D61*
X1130459Y1038198D03*
X1126522Y1016938D03*
X1130459Y1009852D03*
Y995678D03*
X1126522Y988592D03*
X1102113Y1009852D03*
X1098176Y1016938D03*
X1102113Y1038198D03*
X1098176Y988592D03*
X1102113Y995678D03*
G54D23*
X127988Y190242D03*
Y185742D03*
Y194242D03*
Y181742D03*
Y634498D03*
Y638498D03*
Y642998D03*
Y646998D03*
Y1087254D03*
Y1091254D03*
Y1095754D03*
Y1099754D03*
X252200Y190242D03*
Y185742D03*
Y194242D03*
Y181742D03*
Y634498D03*
Y638498D03*
Y642998D03*
Y646998D03*
Y1087254D03*
Y1091254D03*
Y1095754D03*
Y1099754D03*
X376413Y190242D03*
Y185742D03*
Y194242D03*
Y181742D03*
Y638498D03*
Y642998D03*
Y1087254D03*
Y1091254D03*
Y1095754D03*
Y1099754D03*
X500625Y190242D03*
Y185742D03*
Y194242D03*
Y181742D03*
Y638498D03*
Y642998D03*
Y1087254D03*
Y1091254D03*
Y1095754D03*
Y1099754D03*
X624838Y190242D03*
Y185742D03*
Y194242D03*
Y181742D03*
Y638498D03*
Y642998D03*
Y1087254D03*
Y1091254D03*
Y1095754D03*
Y1099754D03*
X749051Y190242D03*
Y185742D03*
Y638498D03*
Y642998D03*
Y1091254D03*
Y1095754D03*
X1070750Y1224035D03*
X1075250D03*
X1070750Y1209862D03*
X1075250D03*
X1070750Y1216949D03*
X1075250D03*
X1070750Y1231122D03*
X1075250D03*
X1070750Y1238209D03*
X1075250D03*
X1070750Y1245295D03*
X1075250D03*
X1070750Y1301988D03*
X1075250D03*
X1070750Y1309075D03*
X1075250D03*
X1070750Y1316161D03*
X1075250D03*
X1070750Y1323248D03*
X1075250D03*
X1070750Y1294902D03*
X1075250D03*
X1070750Y1330335D03*
X1075250D03*
X1070750Y1387028D03*
X1075250D03*
X1070750Y1394114D03*
X1075250D03*
X1070750Y1401201D03*
X1075250D03*
X1070750Y1408287D03*
X1075250D03*
X1070750Y1415374D03*
X1075250D03*
X1070750Y1379941D03*
X1075250D03*
X1278900Y182823D03*
X1274900D03*
X1270400D03*
X1266400D03*
X1261250Y167823D03*
X1256750D03*
X1265250D03*
X1252750D03*
X1278500Y634498D03*
Y638498D03*
Y642998D03*
Y646998D03*
X1259800Y631998D03*
Y627998D03*
Y623498D03*
Y619498D03*
Y1080754D03*
Y1076254D03*
Y1072254D03*
X1278500Y1087254D03*
Y1091254D03*
Y1095754D03*
Y1099754D03*
X1259800Y1084754D03*
X1376963Y167823D03*
X1402713Y181742D03*
Y185742D03*
Y190242D03*
Y194242D03*
X1380963Y167823D03*
X1385463D03*
X1389463D03*
X1402713Y638498D03*
Y642998D03*
X1384013Y627998D03*
Y623498D03*
Y1080754D03*
Y1076254D03*
Y1072254D03*
X1402713Y1087254D03*
Y1091254D03*
Y1095754D03*
Y1099754D03*
X1384013Y1084754D03*
X1511450Y181700D03*
X1506950D03*
X1508225Y627998D03*
Y623498D03*
Y1080754D03*
Y1076254D03*
Y1072254D03*
Y1084754D03*
X1526925Y185742D03*
Y190242D03*
Y638498D03*
Y642998D03*
Y646998D03*
Y1087254D03*
Y1091254D03*
Y1095754D03*
Y1099754D03*
X1651138Y181742D03*
Y185742D03*
Y190242D03*
Y194242D03*
X1632438Y179242D03*
Y175242D03*
Y170742D03*
Y166742D03*
X1651138Y638498D03*
Y642998D03*
X1632438Y627998D03*
Y623498D03*
Y1080754D03*
Y1076254D03*
Y1072254D03*
X1651138Y1087254D03*
Y1091254D03*
Y1095754D03*
Y1099754D03*
X1632438Y1084754D03*
X1756650Y179242D03*
Y175242D03*
Y170742D03*
Y166742D03*
X1725350Y634498D03*
Y638498D03*
Y642998D03*
Y646998D03*
X1731650Y631998D03*
Y627998D03*
Y623498D03*
Y619498D03*
X1756650Y1080754D03*
Y1076254D03*
Y1072254D03*
Y1084754D03*
X1775350Y181742D03*
Y185742D03*
Y190242D03*
Y194242D03*
Y1087254D03*
Y1091254D03*
Y1095754D03*
Y1099754D03*
X1899563Y185742D03*
Y190242D03*
X1880863Y175242D03*
Y170742D03*
X1899563Y634498D03*
Y638498D03*
Y642998D03*
Y646998D03*
X1880863Y631998D03*
Y627998D03*
Y623498D03*
Y619498D03*
Y1080754D03*
Y1076254D03*
Y1072254D03*
X1899563Y1091254D03*
Y1095754D03*
X1880863Y1084754D03*
G54D43*
X1039845Y1467746D03*
X1026345D03*
X1030845D03*
X1035345D03*
X1039845Y1463246D03*
X1026345D03*
X1030845D03*
X1035345D03*
X1005400Y1463157D03*
X1000900D03*
X996400D03*
X1009900D03*
X1005400Y1467657D03*
X1000900D03*
X996400D03*
X1009900D03*
X1035345Y1476746D03*
X1030845D03*
X1026345D03*
X1039845D03*
Y1472246D03*
X1026345D03*
X1030845D03*
X1035345D03*
X1005400Y1472157D03*
X1000900D03*
X996400D03*
X1009900D03*
Y1476657D03*
X1005400D03*
X1000900D03*
X996400D03*
X1023583Y1489593D03*
X995783D03*
X1000500Y1511400D03*
X1036578Y1511210D03*
X1014690Y1511178D03*
X1010190D03*
X1005690D03*
X1031790Y1511078D03*
X1027290D03*
X1019600Y1511100D03*
X1023583Y1501593D03*
Y1507593D03*
Y1495593D03*
X995783D03*
Y1501593D03*
Y1507593D03*
X1040583Y1517883D03*
X1031799Y1534392D03*
X1031882Y1528985D03*
X1026459Y1528919D03*
X1026376Y1534326D03*
X1014867D03*
X1014950Y1528919D03*
X1020290Y1534392D03*
X1020373Y1528985D03*
X1040500Y1529290D03*
X1040583Y1523883D03*
X1062700Y1463100D03*
X1058200D03*
X1067200D03*
X1062700Y1467600D03*
X1058200D03*
X1067200D03*
X1053700Y1463100D03*
Y1467600D03*
X1062700Y1472100D03*
X1058200D03*
X1067200D03*
Y1476600D03*
X1058200D03*
X1062700D03*
X1053700Y1472100D03*
Y1476600D03*
X1078683Y1489593D03*
X1051383D03*
X1041810Y1511084D03*
X1055310D03*
X1059810D03*
X1064310D03*
X1068810D03*
X1073310D03*
X1078683Y1495593D03*
Y1501593D03*
Y1507593D03*
Y1516593D03*
X1051383Y1495593D03*
Y1501593D03*
Y1507593D03*
X1078683Y1522593D03*
G54D14*
X19712Y1176350D03*
X64487Y201761D03*
X53087Y179561D03*
X73437Y247161D03*
Y234661D03*
X49937Y219661D03*
X54437D03*
X58937D03*
X47607Y527511D03*
X61834Y527515D03*
X72500Y508600D03*
X67500D03*
X53087Y632317D03*
X73437Y687417D03*
X64487Y665417D03*
X58937Y672417D03*
X54437D03*
X49937D03*
X64487Y654417D03*
X27143Y663071D03*
X27510Y688422D03*
X73437Y699917D03*
X69500Y777000D03*
X58175Y981325D03*
X70000Y1020000D03*
X64487Y1118173D03*
X58937Y1125173D03*
X54437D03*
X49937D03*
X64487Y1107173D03*
X53027Y1085073D03*
X39325Y1131400D03*
X26723Y1116038D03*
X49437Y1160173D03*
X73437Y1140173D03*
Y1152673D03*
X36848Y1173600D03*
X27090Y1141389D03*
X52000Y1186000D03*
X71500Y1205000D03*
X31500Y1224000D03*
X39425Y1226200D03*
X37225Y1230100D03*
X45518Y1336366D03*
X41381Y1335567D03*
X111437Y195492D03*
X106937Y198543D03*
Y207992D03*
X92287Y194661D03*
X86637Y194861D03*
X95437Y176661D03*
Y181161D03*
X82000Y219000D03*
X111437Y245492D03*
Y235492D03*
X106937Y217441D03*
X111437Y265492D03*
Y275492D03*
X89237Y276861D03*
X95437Y300161D03*
X96000Y336500D03*
X80000Y320000D03*
Y340000D03*
X118437Y314114D03*
X89000Y403500D03*
X100000Y420000D03*
X120000Y440000D03*
X100000D03*
Y460000D03*
X120000D03*
Y480000D03*
X111437Y648248D03*
X92287Y647417D03*
X86637Y647617D03*
X85146Y621637D03*
X95437Y633917D03*
X81500Y672000D03*
X106937Y670197D03*
X111437Y688248D03*
X106937Y660748D03*
Y651299D03*
X111437Y728248D03*
Y718248D03*
Y698248D03*
X89237Y729617D03*
X75500Y757500D03*
X94000Y789000D03*
X118437Y766870D03*
X95437Y752917D03*
X89500Y802500D03*
X90000Y858000D03*
X100000Y880000D03*
Y900000D03*
X120000D03*
Y920000D03*
X100000D03*
X120000Y940000D03*
X111800Y987200D03*
Y983200D03*
X115800Y979200D03*
X119800Y971200D03*
Y975200D03*
Y979200D03*
X115800Y975200D03*
X119800Y987200D03*
Y983200D03*
X115800Y971200D03*
Y983200D03*
Y987200D03*
X119163Y959625D03*
X100000Y940000D03*
X101403Y981195D03*
X97063Y973225D03*
X98563Y977225D03*
X120000Y1025000D03*
X85000Y1020000D03*
X121914Y1003491D03*
X114100Y1002600D03*
X99700Y991400D03*
X108063Y991925D03*
X114300Y992362D03*
X104230Y992209D03*
X74000Y1074000D03*
X85000Y1060000D03*
X111437Y1071004D03*
X118437Y1047382D03*
X95537Y1082173D03*
X81000Y1124500D03*
X106937Y1122953D03*
Y1113504D03*
Y1104055D03*
X111437Y1101004D03*
Y1086004D03*
X92287Y1100173D03*
X86637Y1100373D03*
X74937Y1092973D03*
X95537Y1086673D03*
X111437Y1171004D03*
Y1151004D03*
Y1141004D03*
X118437Y1219626D03*
X111437Y1181004D03*
X89237Y1182373D03*
X95437Y1205673D03*
X130500Y211500D03*
X160500Y190000D03*
X129000Y259000D03*
X142687Y237161D03*
Y248100D03*
X128000Y288500D03*
X160000Y280000D03*
X140000Y300000D03*
X160000D03*
X145437Y265561D03*
X140000Y320000D03*
X160000D03*
X140000Y440000D03*
Y460000D03*
Y480000D03*
Y500000D03*
X164107Y512331D03*
X168365Y516368D03*
X166400Y579400D03*
X168103Y569195D03*
X163763Y561225D03*
X165263Y565225D03*
X142687Y689917D03*
X135200Y738400D03*
X153705Y744831D03*
X153714Y720741D03*
X153757Y710653D03*
X140372Y732370D03*
X150253Y709713D03*
X145437Y717617D03*
X142687Y700767D03*
X140364Y749807D03*
X160000Y880000D03*
Y900000D03*
X140000Y920000D03*
X160000D03*
Y940000D03*
X140000D03*
X137163Y987125D03*
X130463Y983925D03*
X156000Y1032000D03*
X133063Y1012725D03*
X137063Y993725D03*
X145363Y997741D03*
X131110Y993257D03*
X134000Y1064000D03*
X153000Y1105000D03*
X132000Y1117000D03*
X148400Y1086900D03*
X142687Y1142673D03*
X154363Y1161725D03*
X153716Y1174793D03*
X145437Y1165673D03*
X150862Y1152723D03*
X142687Y1153523D03*
X170000Y1190500D03*
X153824Y1197248D03*
X153932Y1182940D03*
X148300Y1228800D03*
X148311Y1182767D03*
X163500Y1345200D03*
X216500Y194756D03*
X210849Y194861D03*
X188699Y212561D03*
Y200561D03*
X177399Y179661D03*
X206000Y219000D03*
X180500Y237000D03*
X197649Y234661D03*
X173649Y254661D03*
X197649Y247161D03*
X174149Y219661D03*
X178649D03*
X183149D03*
X180000Y300000D03*
X213449Y276861D03*
X180000Y320000D03*
Y340000D03*
X200000D03*
X178342Y512294D03*
X182600Y516331D03*
X171861Y527469D03*
X186088Y527473D03*
X196712Y508600D03*
X191712D03*
X210263Y546725D03*
X180800Y590600D03*
X207313Y598113D03*
X203763Y581725D03*
X212063Y585741D03*
X197810Y581257D03*
X174763Y579925D03*
X203863Y575125D03*
X181000Y580362D03*
X170930Y580209D03*
X197163Y571925D03*
X210000Y644000D03*
X185149Y617949D03*
X199763Y600725D03*
X206000Y672000D03*
X197649Y687417D03*
X210000Y650000D03*
X182259Y672559D03*
X177759D03*
X173259D03*
X213449Y729617D03*
X173649Y707417D03*
X197649Y699917D03*
X180000Y860000D03*
Y880000D03*
Y920000D03*
Y900000D03*
X199900Y923200D03*
X188706Y941328D03*
X194206D03*
X184017Y951112D03*
Y945612D03*
X198463Y945525D03*
Y951025D03*
X184295Y1009469D03*
Y1014969D03*
X198741Y1014882D03*
Y1009382D03*
X188552Y1019166D03*
X215563Y1001225D03*
X203563D03*
X207563D03*
X211563D03*
X194052Y1019166D03*
X211000Y1065000D03*
X203500Y1124500D03*
X216499Y1100173D03*
X210849Y1100373D03*
X199149Y1092973D03*
X188399Y1113873D03*
Y1102873D03*
X183149Y1125173D03*
X178649D03*
X174149D03*
X177105Y1094839D03*
X195100Y1096800D03*
X175000Y1143000D03*
X173649Y1160173D03*
X193423Y1140945D03*
X197649Y1152673D03*
X213449Y1182373D03*
X262000Y209000D03*
X235649Y195492D03*
X231991Y198543D03*
X231149Y207992D03*
X219749Y176661D03*
Y181361D03*
X253000Y260000D03*
X266899Y237161D03*
X235649Y245492D03*
Y235492D03*
X231149Y217441D03*
X266899Y248011D03*
X255000Y280000D03*
X235649Y265492D03*
Y275492D03*
X219649Y300161D03*
X242649Y314114D03*
X220000Y360000D03*
X240000Y380000D03*
X220000D03*
Y400000D03*
X240000D03*
Y420000D03*
X220000D03*
Y440000D03*
X240000D03*
Y460000D03*
X220000D03*
Y480000D03*
X240000D03*
Y500000D03*
X220000D03*
X265392Y539225D03*
Y533725D03*
X250586Y533920D03*
Y539420D03*
X260703Y529168D03*
X255203D03*
X220000Y520000D03*
X235649Y648248D03*
X219749Y618917D03*
Y623417D03*
X255500Y664500D03*
X231149Y670197D03*
X235649Y688248D03*
X231149Y660748D03*
Y651299D03*
X266899Y689917D03*
X235649Y728248D03*
Y718248D03*
Y698248D03*
X264739Y732114D03*
X258600Y715500D03*
X266899Y700767D03*
X242649Y766870D03*
X219649Y752917D03*
X248500Y788500D03*
X264731Y749551D03*
X225000Y840000D03*
X245000D03*
X265000Y795000D03*
X225000Y815000D03*
Y880000D03*
X245000D03*
X225000Y860000D03*
X245000D03*
X225000Y900000D03*
X245000D03*
X223100Y920600D03*
X245000Y940000D03*
X239000Y985600D03*
X263000Y1023000D03*
X219563Y1001225D03*
X223563D03*
X252100Y990100D03*
X244600Y1004600D03*
X261100Y1005700D03*
X227063Y994925D03*
X263000Y1047000D03*
X235649Y1071004D03*
X242649Y1047382D03*
X219749Y1082173D03*
X231149Y1122953D03*
Y1113504D03*
Y1104055D03*
X235649Y1101004D03*
Y1086004D03*
X264864Y1120500D03*
X219749Y1086873D03*
X235649Y1171004D03*
Y1151004D03*
X235300Y1142700D03*
X266899Y1141173D03*
X255000Y1207500D03*
X242649Y1219626D03*
X235649Y1181004D03*
X219649Y1205673D03*
X312079Y68379D03*
X303029Y68429D03*
X313628Y112926D03*
X303000Y73500D03*
X314370Y118452D03*
X314439Y133669D03*
X314329Y212420D03*
X312912Y201661D03*
X301612Y179661D03*
X304500Y237000D03*
X297862Y254661D03*
X298362Y219661D03*
X302862D03*
X307362D03*
X300000Y300000D03*
X269649Y266261D03*
X300000Y320000D03*
Y340000D03*
X295000Y400000D03*
Y440000D03*
X291601Y418503D03*
X295000Y460000D03*
X292153Y486059D03*
X306388Y486022D03*
X302513Y512294D03*
X306771Y516331D03*
X292536Y516368D03*
X288278Y512331D03*
X296032Y527469D03*
X310259Y527473D03*
X293763Y582925D03*
X301612Y632417D03*
X312912Y665417D03*
X307362Y672417D03*
X302862D03*
X298362D03*
X312912Y654417D03*
X277972Y744575D03*
X297862Y707417D03*
X277981Y720485D03*
X278024Y710397D03*
X274520Y709457D03*
X286000Y810500D03*
X268100Y982300D03*
X273300Y981700D03*
X280800Y1011900D03*
X281200Y1033000D03*
X305200Y1068400D03*
X295200Y1078400D03*
Y1058400D03*
X271100Y1063200D03*
X281500Y1036744D03*
X281000Y1105000D03*
X312912Y1118273D03*
X307362Y1125173D03*
X302862D03*
X298362D03*
X313232Y1106499D03*
X301327Y1085173D03*
X304500Y1142500D03*
X302452Y1165162D03*
X278577Y1161725D03*
X277930Y1175001D03*
X269649Y1165673D03*
X275385Y1152596D03*
X271165Y1147172D03*
X306000Y1182500D03*
X278076Y1197355D03*
X278146Y1182940D03*
X315500Y1216700D03*
X276100Y1229100D03*
X273243Y1182915D03*
X286925Y1201945D03*
X295900Y1339700D03*
X296100Y1335100D03*
X279900Y1328300D03*
X283700D03*
X286100Y1349659D03*
X292600Y1337367D03*
X289510Y1342259D03*
X354100Y62100D03*
X322500Y68345D03*
X334845Y58745D03*
X361776Y70842D03*
X335081Y104081D03*
X339219Y95188D03*
X339914Y82415D03*
X344304Y82439D03*
X345321Y102400D03*
X347647Y95614D03*
X353001Y114815D03*
X347881Y114881D03*
X351416Y95788D03*
X337641Y114910D03*
X334947Y94605D03*
X342761Y114861D03*
X350441Y117541D03*
X337721Y129821D03*
X323813Y118512D03*
X341114Y123622D03*
X345321Y118921D03*
X323813Y133722D03*
X359862Y195492D03*
X355362Y198543D03*
Y207992D03*
X340712Y194661D03*
X335062Y194861D03*
X344062Y176461D03*
X343962Y181161D03*
X333500Y219000D03*
X359862Y245492D03*
Y235492D03*
X355362Y217441D03*
X321862Y234661D03*
Y247161D03*
X359862Y265492D03*
Y275492D03*
X337662Y276861D03*
X343862Y300161D03*
X352000Y331000D03*
X320000Y340000D03*
X320474Y379474D03*
X316534D03*
X320474Y363234D03*
X316534D03*
X350000Y440000D03*
X330000D03*
X350000Y500000D03*
Y480000D03*
Y460000D03*
X330000D03*
X320925Y485385D03*
X315925D03*
X330000Y540000D03*
X350000D03*
Y520000D03*
X320925Y508600D03*
X315925D03*
X333000Y560000D03*
X350000D03*
X340712Y647517D03*
X335062Y647617D03*
X333682Y621858D03*
X343862Y633917D03*
X330000Y672000D03*
X321862Y687417D03*
X337662Y729617D03*
X321862Y699917D03*
X320000Y750000D03*
X330000Y770000D03*
X347000Y788500D03*
X343862Y752917D03*
X320474Y832229D03*
X316534D03*
X330000Y900000D03*
X320925Y938140D03*
X315600Y933600D03*
X335300Y926900D03*
X360000Y960000D03*
X330000D03*
X337100Y972100D03*
X322000Y988500D03*
X362000Y1017000D03*
X344737Y995637D03*
X350673Y1031200D03*
X328000Y1061000D03*
X359862Y1071004D03*
X344062Y1082073D03*
X355362Y1122953D03*
Y1113504D03*
Y1104055D03*
X359862Y1101004D03*
Y1086004D03*
X340812Y1100273D03*
X335062Y1100373D03*
X323362Y1092973D03*
X344062Y1086773D03*
X358518Y1171114D03*
X359862Y1151004D03*
Y1141004D03*
X321862Y1140173D03*
Y1152673D03*
X331679Y1175800D03*
X327500Y1197000D03*
X359862Y1181004D03*
X337662Y1182373D03*
X343862Y1205673D03*
X377144Y84720D03*
X377944Y95929D03*
X386000Y209000D03*
X390312Y237161D03*
X390412Y248011D03*
X389000Y289000D03*
X386800Y263800D03*
X385500Y313000D03*
X366862Y314114D03*
X390000Y500000D03*
X370000D03*
X390000Y540000D03*
Y520000D03*
X370000D03*
Y540000D03*
X390000Y560000D03*
X370000D03*
X393862Y719917D03*
X398677Y709385D03*
X391112Y700767D03*
X388788Y749479D03*
X407714Y761291D03*
X398254Y763517D03*
X380000Y960000D03*
X393500Y988500D03*
Y1017000D03*
X408672Y1008038D03*
X390000Y1055000D03*
X366862Y1047382D03*
X388888Y1118173D03*
X391112Y1142673D03*
X399474Y1166787D03*
X385210Y1166347D03*
X393679Y1157480D03*
X383191Y1170203D03*
X391112Y1153500D03*
X366862Y1219626D03*
X406037Y1192706D03*
X402403Y1188312D03*
X398527Y1188659D03*
Y1233336D03*
X437124Y212661D03*
Y201661D03*
X429224Y176300D03*
X446074Y247161D03*
X422300Y254661D03*
X446074Y234661D03*
X431574Y219661D03*
X427074D03*
X422574D03*
X441645Y288847D03*
Y284647D03*
X456190Y354105D03*
X444687Y379474D03*
X440747D03*
X444687Y363234D03*
X440747D03*
X452800Y420912D03*
X418600Y445462D03*
X421700Y450200D03*
X445138Y487743D03*
X440138D03*
X447533Y475900D03*
X458679Y470700D03*
X450500Y459562D03*
X416303Y486022D03*
X430538Y485985D03*
X430000Y545500D03*
X460000Y540000D03*
X426663Y512257D03*
X430921Y516294D03*
X416686Y516331D03*
X412428Y512294D03*
X420182Y527432D03*
X434409Y527436D03*
X460000Y600000D03*
X445000D03*
X440000Y560000D03*
X460000D03*
X440000Y613000D03*
X459274Y647617D03*
X447574Y640217D03*
X425824Y632317D03*
X457853Y622091D03*
X437224Y654417D03*
X431574Y672417D03*
X427074D03*
X422574D03*
X444687Y832229D03*
X440747D03*
X444687Y816765D03*
X440747D03*
X445138Y938140D03*
X440138D03*
X435082Y915200D03*
X437600Y917800D03*
X445582Y925352D03*
X449137Y967757D03*
X428000Y988500D03*
X429613Y1017920D03*
X432657Y1015102D03*
X442600Y998300D03*
X413000Y1054200D03*
X442473Y1068726D03*
X447173D03*
X424000Y1105000D03*
X453473Y1089300D03*
X456919Y1121725D03*
X447919D03*
X452419D03*
X441976Y1107576D03*
X446627Y1112973D03*
X418500Y1176800D03*
X437104Y1160696D03*
X441400Y1169400D03*
X450500Y1208500D03*
X424000Y1206000D03*
X416900Y1221800D03*
X412300Y1326200D03*
X415422Y1352000D03*
X422373Y1359747D03*
X418922Y1356522D03*
X480159Y201245D03*
X500184Y200328D03*
X478306Y195593D03*
X461122Y194861D03*
X462200Y173109D03*
X468472Y182441D03*
X484074Y245492D03*
X478651Y220734D03*
X484074Y235492D03*
Y275492D03*
X481174Y265492D03*
X461874Y276861D03*
X468074Y300161D03*
X491074Y314114D03*
X470000Y400000D03*
Y380000D03*
Y430000D03*
X465000Y491000D03*
X462133Y473300D03*
X481533Y480875D03*
X506746Y512331D03*
X497351Y531531D03*
X501023Y534941D03*
X499000Y553000D03*
X491074Y594626D03*
X472022Y582062D03*
X484074Y648248D03*
Y633248D03*
Y618248D03*
X464924Y647417D03*
X468174Y633917D03*
X479574Y660748D03*
Y651299D03*
X500000Y960000D03*
X480000D03*
X504000Y988500D03*
X462000D03*
X465200Y1018200D03*
X468000Y1047000D03*
X484074Y1071004D03*
X491074Y1047382D03*
X460673Y1071976D03*
X460873Y1077526D03*
X506500Y1051900D03*
X465346Y1122953D03*
X479574Y1113504D03*
Y1104055D03*
X484074Y1101004D03*
Y1086004D03*
X504724Y1118073D03*
Y1107073D03*
X484074Y1171004D03*
Y1151004D03*
Y1141004D03*
X506700Y1141973D03*
X505874Y1134773D03*
X506700Y1145973D03*
X502500Y1211500D03*
X476373Y1219498D03*
X484074Y1181004D03*
X461874Y1182373D03*
X468074Y1205673D03*
X509180Y145419D03*
X546009Y187821D03*
X539584Y184694D03*
X542155Y187543D03*
X519868Y242334D03*
X557057Y220152D03*
X553674Y220121D03*
X550219Y220111D03*
X515324Y252511D03*
X515500Y301000D03*
X550987Y262810D03*
X553742Y267705D03*
X510700Y277200D03*
X548500Y343000D03*
X515000Y322500D03*
X534905Y354105D03*
X547500Y440000D03*
X539350Y487659D03*
X534350D03*
X510621Y486059D03*
X524856Y486022D03*
X520981Y512294D03*
X549279Y513331D03*
X525579Y538331D03*
X557279Y513331D03*
X525239Y516331D03*
X511004Y516368D03*
X518700Y548700D03*
X553279Y523331D03*
X514500Y524469D03*
X528727Y524973D03*
X553279Y513331D03*
X530130Y547167D03*
X540000Y583000D03*
Y600000D03*
X520000D03*
X533879Y566031D03*
X548767Y556819D03*
X520579Y553231D03*
X517499Y576931D03*
X557279Y570331D03*
X527179Y568731D03*
X528000Y611000D03*
X532000Y623000D03*
X549937Y632317D03*
X555787Y672417D03*
X551287D03*
X546787D03*
X509996Y716996D03*
X522773Y709638D03*
X515324Y700667D03*
X512884Y749732D03*
X525500Y967000D03*
X530800Y1028300D03*
X515800Y1028000D03*
X523000Y1045000D03*
X528500Y1073500D03*
X556022Y1042817D03*
X552436Y1042494D03*
X546787Y1125173D03*
X551287D03*
X555787D03*
X549773Y1085173D03*
X546287Y1160173D03*
X535320Y1152771D03*
X534874Y1139774D03*
X526523Y1177122D03*
X526501Y1166546D03*
X509037Y1136700D03*
X524828Y1159231D03*
X526388Y1197747D03*
X526367Y1183111D03*
X522867Y1190284D03*
Y1231097D03*
X520600Y1324100D03*
X536000Y1359826D03*
X541362D03*
X518397Y1360000D03*
X512900Y1345600D03*
X553587Y1346026D03*
X527000Y1340600D03*
X521500Y1342800D03*
X603787Y207992D03*
X604517Y196263D03*
X586719Y196888D03*
X583487Y194861D03*
X566271Y167387D03*
X561437Y197249D03*
X592767Y179277D03*
X598236Y181981D03*
X588188Y216520D03*
X570287Y234661D03*
X563000Y217600D03*
X569009Y247887D03*
X592287Y300161D03*
X582758Y276861D03*
X590000Y342000D03*
X568899Y379474D03*
X564959D03*
X568899Y363234D03*
X564959D03*
X560000Y438500D03*
X594500Y462000D03*
X569529Y502127D03*
X575700Y528831D03*
X563279Y506731D03*
X602379Y547831D03*
X570779Y542831D03*
X568779Y512831D03*
X575779D03*
X593079Y516531D03*
Y512531D03*
X585479Y537731D03*
Y543994D03*
X572229Y520081D03*
X580279Y512831D03*
X592000Y595000D03*
X580000Y600000D03*
X560000D03*
X571408Y577450D03*
X584279Y577431D03*
X575779D03*
X579718D03*
X592779D03*
X588779D03*
X562279D03*
X567641Y577473D03*
X571529Y562951D03*
X579529D03*
X602779Y552331D03*
X586000Y611000D03*
X589137Y647417D03*
X583487Y647617D03*
X571787Y640217D03*
X592387Y629417D03*
Y634017D03*
X603787Y660748D03*
Y651299D03*
X561437Y654417D03*
X568899Y832229D03*
X564959D03*
X593365Y877358D03*
X592614Y882300D03*
X569350Y941640D03*
X564350D03*
X589500Y988000D03*
X571000D03*
X571400Y1000100D03*
X575000Y1057500D03*
X586500Y1061500D03*
X586000Y1046500D03*
X575000Y1046000D03*
X592387Y1082173D03*
X561337Y1120873D03*
X583487Y1100373D03*
X571787Y1092973D03*
X589137Y1100173D03*
X603787Y1122953D03*
Y1113504D03*
Y1104055D03*
X561337Y1107173D03*
X592387Y1086873D03*
X570287Y1140173D03*
Y1152673D03*
X600640Y1171000D03*
X567500Y1189500D03*
X586087Y1182373D03*
X592287Y1205673D03*
X592400Y1214456D03*
X607929Y112329D03*
X619171D03*
X639537Y237161D03*
X608287Y245492D03*
Y235492D03*
X639537Y248011D03*
X649500Y285000D03*
X608287Y275492D03*
X607961Y263934D03*
X642287Y266461D03*
X650000Y322500D03*
X615287Y314114D03*
X649000Y429500D03*
X652663Y502400D03*
X647663D03*
X612000Y502300D03*
X624028Y503558D03*
X638263Y503494D03*
X643000Y549500D03*
X620153Y511994D03*
X634388Y511957D03*
X615100Y513287D03*
X638646Y515994D03*
X624411Y516031D03*
X615119Y551586D03*
X627000Y538581D03*
Y542909D03*
X609334Y538306D03*
Y543306D03*
X619560Y547201D03*
X627863Y522000D03*
X642509Y520667D03*
X615287Y594626D03*
X615147Y565956D03*
X637213Y582155D03*
X623236Y562574D03*
X608287Y648248D03*
Y633248D03*
Y618248D03*
X642287Y719817D03*
X647207Y709555D03*
X639537Y700767D03*
X637318Y749649D03*
X634000Y988000D03*
X638500Y1046500D03*
X608287Y1071004D03*
X615287Y1047382D03*
X645200Y1067800D03*
X608287Y1101004D03*
Y1086004D03*
X643000Y1146173D03*
X608287Y1171004D03*
Y1151004D03*
Y1141004D03*
X651216Y1164051D03*
X636803Y1167864D03*
X642942Y1156818D03*
X632603Y1136225D03*
X647716Y1154150D03*
X639537Y1153523D03*
X615238Y1218951D03*
X608287Y1181004D03*
X650644Y1197038D03*
X650626Y1182447D03*
X627632Y1217300D03*
X647126Y1189513D03*
X687566Y109568D03*
X663449Y115606D03*
X690807Y103298D03*
X695137Y189130D03*
X685545Y212806D03*
X677450Y185669D03*
X685250Y199493D03*
X689426Y236628D03*
X694500Y247161D03*
X670500Y254661D03*
X674313Y220374D03*
X669813D03*
X673500Y344000D03*
X689232Y355251D03*
X693112Y385976D03*
X689172D03*
Y358978D03*
X698500Y415500D03*
X695500Y462500D03*
X670000Y531500D03*
X658646Y515180D03*
X696787Y580633D03*
X658681Y571798D03*
X654681D03*
X683341Y580479D03*
X689747D03*
X696000Y641717D03*
X682000Y628449D03*
X685550Y654417D03*
X679929Y673058D03*
X675429D03*
X670929D03*
X658574Y930100D03*
X677457Y944796D03*
X688563Y961355D03*
X693563D03*
X663800Y1018300D03*
X682200Y1026500D03*
X674300Y1001620D03*
X696000Y1092973D03*
X685250Y1113673D03*
Y1102873D03*
X680000Y1125173D03*
X675500D03*
X671000D03*
X674700Y1098500D03*
X667700Y1160173D03*
X694500Y1140173D03*
X692671Y1152747D03*
X668000Y1195000D03*
X680500Y1208500D03*
X664000Y1278100D03*
X673000Y1354100D03*
X724645Y138941D03*
X732500Y165492D03*
X707700Y194861D03*
X713350Y194661D03*
X747242Y197553D03*
X717188Y176461D03*
X716600Y181161D03*
X710300Y276861D03*
X716500Y300161D03*
X705348Y478425D03*
X702500Y563000D03*
X713350Y647417D03*
X716600Y629417D03*
Y633917D03*
X707700Y649117D03*
X724283Y860689D03*
X737984Y861689D03*
X741883Y861389D03*
X733883Y935689D03*
X736883Y938689D03*
Y929189D03*
Y933689D03*
X747383Y924689D03*
X733883Y940689D03*
X736462Y948996D03*
X736883Y943189D03*
X712000Y1046000D03*
X716600Y1081973D03*
X713350Y1100173D03*
X707700Y1100373D03*
X716600Y1086673D03*
X716000Y1136000D03*
X732500Y1171004D03*
Y1151004D03*
X739500Y1219626D03*
X732500Y1181004D03*
X710300Y1182373D03*
X716500Y1205673D03*
X728174Y1275611D03*
X725678Y1272799D03*
X722790Y1270557D03*
X720446Y1267427D03*
X731500Y1277811D03*
X780000Y40000D03*
X760000Y60000D03*
X780000D03*
X757020Y159692D03*
X758619Y168537D03*
X767405Y210364D03*
X763188Y172500D03*
X789739Y365493D03*
X754500Y668741D03*
X755000Y677700D03*
X765124Y864089D03*
X766707Y872260D03*
X762453Y872413D03*
X765025Y867802D03*
X757664Y868974D03*
X753893Y912630D03*
X776400Y956500D03*
X780800Y959300D03*
X786800Y1016000D03*
X784000Y1024000D03*
X759500Y1056100D03*
X779535Y1180469D03*
X792263Y1178661D03*
Y1174461D03*
Y1170261D03*
X752500Y1167500D03*
X756250Y1151750D03*
X752000Y1197500D03*
X756000Y1225500D03*
X784544Y1210178D03*
Y1205978D03*
X779535Y1193469D03*
Y1189269D03*
Y1184669D03*
X797177Y1189537D03*
X797225Y1185337D03*
X792263Y1182861D03*
X770000Y1231500D03*
X769500Y1283500D03*
X792336Y1319537D03*
X782230Y1323670D03*
X769728Y1325747D03*
X785340Y1320410D03*
X789549Y1322310D03*
X777009Y1322690D03*
X781290Y1328490D03*
X772900Y1328550D03*
X790290Y1328410D03*
X785640Y1328370D03*
X796848Y1469724D03*
X829921Y-458D03*
X825984D03*
X833724Y-3346D03*
X833671Y254D03*
X806299Y-458D03*
X802362D03*
X814173D03*
X810236D03*
X822047D03*
X818110D03*
X845661Y-3642D03*
X843463Y530D03*
X802102Y51075D03*
X799102Y48575D03*
X802102Y46075D03*
X799102Y43575D03*
X802102Y41075D03*
X845961Y56762D03*
Y52762D03*
X838521Y41568D03*
X838043Y37217D03*
X806314Y35952D03*
X802350Y35923D03*
X842470Y41295D03*
X841733Y36654D03*
X810301Y78654D03*
X805301D03*
X802801Y75654D03*
X807801D03*
X812801D03*
X846400Y473900D03*
X839500Y508500D03*
X809015Y661000D03*
X804015D03*
X808920Y652340D03*
Y656460D03*
X806515Y664000D03*
X827000Y1168000D03*
X802036Y1164244D03*
X803438Y1139700D03*
X802500Y1194500D03*
X807500D03*
X812500D03*
X810000Y1191500D03*
X805000D03*
X809600Y1236300D03*
X804600D03*
X802100Y1233300D03*
X807100D03*
X812100D03*
X806952Y1460496D03*
X806568Y1464275D03*
X802433Y1461619D03*
X800900Y1465234D03*
X800462Y1469231D03*
X834813Y1528889D03*
X834974Y1533243D03*
X886322Y69D03*
X867080Y393D03*
X886427Y3802D03*
X873892Y287D03*
X886418Y-7350D03*
X849484Y649D03*
X886351Y-3735D03*
X857513Y659D03*
X849961Y52762D03*
X885448Y37380D03*
X877265Y52540D03*
X881265D03*
X885265D03*
X873265D03*
X869265D03*
X869459Y56626D03*
Y61626D03*
X869044Y66985D03*
X873044D03*
X877139Y66926D03*
X885265Y60540D03*
Y56540D03*
X881750Y37397D03*
X886073Y78824D03*
X885464Y83201D03*
X878549Y78905D03*
Y82905D03*
X869044Y70985D03*
X873044D03*
X882549Y76905D03*
Y80905D03*
X872796Y251714D03*
X881549Y326304D03*
X890982Y349498D03*
X874800Y355798D03*
X887100Y359100D03*
X887500Y378495D03*
X875132Y399200D03*
X878732D03*
Y395600D03*
X875132D03*
X878732Y392000D03*
X875132D03*
X880932Y406400D03*
Y402800D03*
X877332Y406400D03*
Y402800D03*
X874807Y375193D03*
X866276Y454900D03*
X866317Y446725D03*
X880932Y410000D03*
X877332D03*
X857300Y454300D03*
X862000Y453600D03*
X852000Y454200D03*
X866321Y451300D03*
X878500Y476000D03*
X878193Y467707D03*
X866278Y459562D03*
X870600Y476900D03*
X851800Y477200D03*
X874715Y707651D03*
X871115D03*
X867515D03*
X884700Y705200D03*
X881100D03*
X877500D03*
X887600Y811900D03*
X891200Y838200D03*
X878673Y804527D03*
X874569Y811300D03*
X885882Y861618D03*
X894965Y843500D03*
X877673Y868873D03*
X888962Y843262D03*
X873647Y861653D03*
X882333Y896320D03*
X895616Y985932D03*
X863800Y1309876D03*
X885301Y1358557D03*
X884746Y1350438D03*
X873495Y1370213D03*
X885300Y1371050D03*
X872164Y1350464D03*
X873259Y1365805D03*
X872181Y1354764D03*
X886792Y1404100D03*
X873918Y1411149D03*
X882226Y1404197D03*
X873694Y1404575D03*
X873700Y1375746D03*
X873570Y1380401D03*
X877300Y1432400D03*
X886500Y1432500D03*
X893158Y1516542D03*
X893050Y1489500D03*
X868791Y1478782D03*
X888800Y1493500D03*
X876514Y1514948D03*
X863851Y1501681D03*
X877828Y1500379D03*
X892966Y1508549D03*
X893036Y1512600D03*
X877946Y1496527D03*
X876096Y1505499D03*
X860179Y1491170D03*
X892682Y1520718D03*
X893020Y1566530D03*
X876200Y1553900D03*
X892700Y1543900D03*
X892558Y1528458D03*
X889300Y1551000D03*
X876190Y1537187D03*
X876100Y1549000D03*
X876200Y1558400D03*
X892700Y1524700D03*
X848551Y1542440D03*
X922687Y93D03*
X928138Y-8453D03*
X942000Y752850D03*
X897000Y839000D03*
X915000Y879000D03*
X903000Y842500D03*
X926185Y928342D03*
X924974Y933041D03*
X895869Y932822D03*
X914876Y901029D03*
X937621Y915324D03*
X920810Y902210D03*
X928100Y900650D03*
X900615Y909723D03*
X902571Y906534D03*
X903368Y934568D03*
X904594Y931141D03*
X916204Y938572D03*
X917550Y934742D03*
X901540Y937712D03*
X896679Y927505D03*
X896420Y916712D03*
X898468Y912970D03*
X931085Y936172D03*
X941274Y900845D03*
X924563Y962945D03*
X919759Y970868D03*
X938009Y987330D03*
X941868Y952101D03*
X934142Y974344D03*
X939481Y980230D03*
X912994Y971921D03*
X910397Y979189D03*
X902991Y982230D03*
X909826Y982874D03*
X905271Y974586D03*
X899846Y971468D03*
X898617Y975434D03*
X895837Y978389D03*
X896629Y982285D03*
X935623Y971054D03*
X898920Y1020000D03*
X916446Y1035438D03*
X941640Y995820D03*
X904601Y998556D03*
X910040Y1006613D03*
X911807Y1002342D03*
X919656Y998764D03*
X939544Y1003485D03*
X903442Y1003265D03*
X896371Y1002112D03*
X936378Y1035722D03*
X929257Y1035883D03*
X920770Y1067389D03*
X921149Y1062424D03*
X914948Y1063255D03*
X908477Y1061823D03*
X910387Y1055344D03*
X904875Y1051177D03*
X906000Y1222000D03*
X924500Y1236000D03*
X942925Y1369010D03*
X928384Y1346435D03*
X932559Y1360137D03*
X928439Y1360167D03*
X932564Y1346100D03*
X896500Y1341800D03*
X936959Y1360143D03*
X896212Y1345788D03*
X932294Y1379995D03*
X928194D03*
X895900Y1390100D03*
X896200Y1386000D03*
X896100Y1393800D03*
X896200Y1397900D03*
Y1405300D03*
X896100Y1401600D03*
X923829Y1389012D03*
X936994Y1379895D03*
X927601Y1384433D03*
X923486Y1384268D03*
X904941Y1456941D03*
X906600Y1461600D03*
X909400Y1459200D03*
X910000Y1464900D03*
X905500Y1467161D03*
X932500Y1493200D03*
X926500Y1499700D03*
X918500D03*
X938000Y1499200D03*
X942000Y1499500D03*
X922500Y1499700D03*
X908742Y1477427D03*
X908542Y1481127D03*
X922500Y1509700D03*
X906000Y1543700D03*
X918505Y1530405D03*
X918800Y1534500D03*
X941000Y1564200D03*
X937000D03*
X926500Y1556700D03*
X931500Y1564200D03*
X913250Y1547700D03*
X940000Y1529200D03*
X940750Y1549200D03*
X900000Y1526500D03*
X897400Y1574000D03*
X897038Y1577600D03*
X911516Y1573202D03*
X911616Y1576802D03*
X911710Y1582375D03*
X911094Y1585923D03*
X924059Y1647700D03*
X981700Y-115500D03*
X976713Y-115570D03*
X991713Y-115413D03*
X989316Y-94984D03*
X992185Y-54411D03*
X989050Y-70850D03*
X990565Y130230D03*
Y135230D03*
Y125230D03*
X985688Y362549D03*
X977794Y695103D03*
X952200Y742600D03*
X957100Y742900D03*
X977622Y699464D03*
X953200Y736700D03*
X956900Y737600D03*
X949048Y755225D03*
X952476Y753652D03*
X951300Y747900D03*
X956200Y748200D03*
X957320Y769818D03*
X947866Y763541D03*
X957629Y766231D03*
X952820Y769518D03*
X944500Y760750D03*
X962900Y905000D03*
X981580Y932678D03*
X953967Y933635D03*
X961100Y931640D03*
X960503Y936185D03*
X967583Y933607D03*
X968698Y928957D03*
X974484Y935078D03*
X976419Y931628D03*
X976460Y927891D03*
X981679Y936678D03*
X976213Y938846D03*
X966000Y937500D03*
X976580Y986180D03*
X948942Y974655D03*
X961134Y976191D03*
X959400Y960300D03*
X953013Y960147D03*
X947174Y957150D03*
X979020Y960000D03*
Y956200D03*
X973900Y960000D03*
Y956200D03*
X968780Y960000D03*
Y956200D03*
X987734Y979575D03*
X946138Y1006299D03*
X987970Y1004157D03*
X955700Y1030700D03*
X951200D03*
X946700D03*
X947759Y998726D03*
X961220Y1001600D03*
Y1005400D03*
X966340Y1001600D03*
Y1005400D03*
X971460Y1001600D03*
Y1005400D03*
X974020Y1026200D03*
Y1022400D03*
X968900Y1026200D03*
Y1022400D03*
X963780Y1026200D03*
Y1022400D03*
X956600Y1001700D03*
Y1005700D03*
X977400Y1157900D03*
X964537Y1160310D03*
X958870Y1163617D03*
X962941Y1165929D03*
X967497Y1168802D03*
X957871Y1171219D03*
X963000Y1174427D03*
X969463Y1177599D03*
X972924Y1158033D03*
X954395Y1145604D03*
X977500Y1182300D03*
X982387Y1183598D03*
X962500Y1298500D03*
X947125Y1369010D03*
X951525Y1369107D03*
X955500Y1369000D03*
X944921Y1515200D03*
X988624Y1502923D03*
X951815Y1491459D03*
X946300Y1499300D03*
X969198Y1505851D03*
X969472Y1501978D03*
X950300Y1499500D03*
X975813Y1556916D03*
X953500Y1563200D03*
X962000Y1564200D03*
X958000D03*
X949000D03*
X945000D03*
X972001Y1533926D03*
X975813Y1545916D03*
X954700Y1524100D03*
Y1530363D03*
X974787Y1525100D03*
Y1529300D03*
X948750Y1549200D03*
X979963Y1545689D03*
X1034916Y-82413D03*
Y-87913D03*
X1011984Y-83066D03*
X1012174Y-88726D03*
X1004213Y-95837D03*
X998045Y-79300D03*
X993816Y-95184D03*
X1015582Y-69800D03*
X1014800Y-62100D03*
X999300Y-64400D03*
X1009100Y-48600D03*
X1035000Y-66800D03*
X1022618Y-36900D03*
X1023300Y-44200D03*
X1032053Y-34953D03*
X1038712Y-34812D03*
X1007582Y-39418D03*
X1000300Y-74200D03*
X1032080Y-45980D03*
X1004082Y-38200D03*
X1000418Y-69982D03*
X993000Y-60600D03*
X1019118Y-34382D03*
X1019082Y-71000D03*
X1026717Y-11646D03*
X1021086Y-11682D03*
X1017600Y63600D03*
Y58900D03*
Y54200D03*
X1010650Y49950D03*
Y67650D03*
X1036003Y93543D03*
X1038503Y97543D03*
X1033503D03*
Y102543D03*
Y107543D03*
Y112543D03*
X1030775Y130016D03*
X1030890Y137780D03*
X993565Y137730D03*
Y132730D03*
Y127730D03*
X1030774Y133840D03*
X1030758Y126274D03*
X1030825Y122335D03*
X1020250Y357188D03*
X998000Y378000D03*
X1040180Y437510D03*
X1018322Y545207D03*
X1018300Y550000D03*
X1025000Y817000D03*
X1028472Y834829D03*
X1027063Y850703D03*
X1031563Y852453D03*
X1038215Y877191D03*
X1034271Y876911D03*
X1011100Y904600D03*
X1025000Y897700D03*
X1036431Y929752D03*
X1037083Y933300D03*
X1016842Y916445D03*
X1014891Y943357D03*
X1013713Y974651D03*
X997694Y974940D03*
X1035947Y948800D03*
X1025774Y1001538D03*
X992994Y1005740D03*
X1012494Y1033840D03*
X1028657Y1009103D03*
X1020654Y1023940D03*
X1018094Y1021240D03*
X1015534Y1023840D03*
X1007849Y1033743D03*
X996600D03*
X1012974Y1021240D03*
X1013700Y1007640D03*
X1009509Y1009850D03*
X1037282Y995028D03*
X1005294Y997940D03*
Y1001740D03*
X1010414Y997940D03*
Y1001740D03*
X1023214Y1007140D03*
X1007372Y1023832D03*
X1017194Y1033840D03*
X1018000Y1076500D03*
X1037000Y1067100D03*
X1032500D03*
X1017000Y1093950D03*
X1021200Y1094300D03*
X1031400Y1124700D03*
X1026900Y1129466D03*
X1022400Y1129183D03*
X1036160Y1095500D03*
Y1091700D03*
Y1111900D03*
X1019000Y1178000D03*
X1013400Y1137500D03*
X1021991Y1141526D03*
X1004294Y1137600D03*
X994923Y1137488D03*
X997500Y1192500D03*
X1006800Y1191200D03*
X995948Y1184250D03*
X1017354Y1196124D03*
X1021061Y1198543D03*
X1032500Y1248000D03*
X993500Y1317000D03*
X1016835Y1323916D03*
X1025335Y1324216D03*
X1031000Y1350500D03*
X1031474Y1354526D03*
X1016672Y1338228D03*
X1025284Y1341216D03*
X1025335Y1337616D03*
Y1330916D03*
X1016600Y1332000D03*
X1033000Y1416125D03*
X1028000Y1404700D03*
Y1411000D03*
X1031500Y1408000D03*
X1020854Y1455075D03*
X1016854D03*
X1065621Y-85082D03*
X1046713Y-115570D03*
X1076713D03*
X1084200Y-82300D03*
X1074400Y-81000D03*
X1051713Y-114887D03*
X1056713Y-115413D03*
X1086713Y-115570D03*
X1081713D03*
X1071713D03*
X1066713D03*
X1041713Y-115465D03*
X1070500Y-67900D03*
X1074400Y-39100D03*
X1079600Y-50700D03*
X1087700Y-37886D03*
X1045800Y-75936D03*
X1058333Y-72770D03*
X1061325Y-40378D03*
X1054625Y-40278D03*
X1079455Y-30742D03*
X1043000Y-67600D03*
X1043112Y-34912D03*
X1078900Y-45782D03*
X1070918Y-73618D03*
X1076000Y-10500D03*
X1043303Y-27685D03*
X1045873Y-24660D03*
X1043513Y-21696D03*
X1077505Y22405D03*
X1076418Y31082D03*
X1076944Y35182D03*
X1077260Y42612D03*
X1077400Y52000D03*
X1077082Y38982D03*
X1076905Y46195D03*
X1076299Y27282D03*
X1078500Y99000D03*
X1043703Y112543D03*
Y107543D03*
Y102543D03*
X1041003Y93543D03*
X1043703Y97543D03*
X1062854Y83434D03*
X1078500Y135500D03*
X1043500Y310500D03*
X1048500Y346000D03*
X1058500Y368500D03*
X1045000Y364000D03*
X1050100Y392600D03*
Y397600D03*
Y402600D03*
X1044600Y392500D03*
Y397500D03*
Y402500D03*
X1041500Y382858D03*
X1078100Y392600D03*
Y397600D03*
Y402600D03*
X1072600Y392500D03*
Y397500D03*
Y402500D03*
X1045292Y384688D03*
X1044600Y407500D03*
X1050100Y407600D03*
X1042833Y434409D03*
X1074425Y447225D03*
X1071950Y453288D03*
X1072600Y407500D03*
X1078100Y407600D03*
X1043674Y451921D03*
X1043500Y446600D03*
X1047000Y492000D03*
X1079000Y477000D03*
X1058000D03*
X1069018Y456900D03*
X1065985Y460500D03*
X1045106Y561249D03*
X1058000Y616000D03*
X1073000Y676000D03*
X1047000Y751000D03*
X1045163Y840400D03*
X1082000Y815500D03*
X1054419Y839493D03*
Y828081D03*
X1050763Y829163D03*
X1086600Y833200D03*
X1054000Y866000D03*
X1075500Y848000D03*
X1044680Y921400D03*
X1053200Y901703D03*
X1043882Y901568D03*
X1044101Y927130D03*
X1083633Y932172D03*
X1073408Y942399D03*
X1058571Y943852D03*
X1053099Y1021657D03*
X1048512Y1021378D03*
X1041616Y997225D03*
X1052000Y1054000D03*
X1082500Y1067100D03*
X1073500D03*
X1054080Y1077680D03*
X1069000Y1067100D03*
X1064500Y1096150D03*
X1068700Y1096600D03*
X1087700Y1125800D03*
X1083355Y1125903D03*
X1070155D03*
X1048960Y1113900D03*
Y1117700D03*
X1041280Y1121500D03*
Y1113900D03*
Y1117700D03*
X1081078Y1095362D03*
X1083660Y1092700D03*
X1041280Y1095500D03*
Y1091700D03*
Y1100500D03*
X1048960Y1095500D03*
Y1091700D03*
Y1099300D03*
X1054080Y1113900D03*
Y1117700D03*
X1068700Y1108700D03*
X1083355Y1116103D03*
X1070155D03*
X1075600Y1179090D03*
X1053743Y1174221D03*
X1046900Y1168000D03*
X1052522Y1145153D03*
X1076032Y1191144D03*
X1070000Y1184100D03*
X1079500Y1276100D03*
X1047000Y1258687D03*
X1051300Y1253300D03*
X1077300Y1271700D03*
X1042343Y1324216D03*
X1048251Y1349992D03*
X1046372Y1356326D03*
X1042343Y1337616D03*
X1042443Y1342668D03*
X1042343Y1330916D03*
X1076754Y1455075D03*
X1072754D03*
X1044654D03*
X1048654D03*
X1134500Y-103500D03*
X1117535Y-115157D03*
X1115000Y-77500D03*
X1097600Y-82462D03*
X1107700Y-76800D03*
X1100929Y-90371D03*
X1116600Y-85538D03*
X1106300Y-94800D03*
X1089318Y-91682D03*
X1114400Y-55662D03*
X1093900Y-64500D03*
X1113300Y-44100D03*
X1101246Y-31005D03*
X1124024Y-30840D03*
X1128765Y-34297D03*
X1094200Y-38400D03*
X1111254Y-31020D03*
X1105328Y-31005D03*
X1094300Y-60300D03*
X1103300Y-60000D03*
X1115603Y-60293D03*
X1134110Y176500D03*
X1136203Y167600D03*
X1089300Y836100D03*
X1119159Y878130D03*
Y873130D03*
Y868130D03*
X1116159Y870630D03*
Y875630D03*
X1119419Y888607D03*
X1100847Y905617D03*
X1105847D03*
X1110847D03*
X1108347Y902617D03*
X1103347D03*
X1116419Y896107D03*
Y891107D03*
X1119419Y893607D03*
Y898607D03*
X1110447Y944217D03*
X1105447D03*
X1100447D03*
X1102947Y947217D03*
X1107947D03*
X1119700Y1067200D03*
X1124500D03*
X1091400Y1070900D03*
X1091494Y1075994D03*
X1097800Y1070700D03*
X1097500Y1075100D03*
X1103800Y1070600D03*
Y1075600D03*
X1128900Y1067200D03*
X1101580Y1091120D03*
X1107100Y1096050D03*
X1111600Y1097800D03*
X1124100Y1125100D03*
X1119500D03*
X1115000D03*
X1123600Y1096400D03*
X1123838Y1092800D03*
X1123600Y1100000D03*
X1133981Y1096283D03*
X1134002Y1092600D03*
X1134103Y1099881D03*
X1137436Y1124750D03*
X1128800Y1125100D03*
X1092200Y1125800D03*
X1103064Y1113626D03*
X1099020Y1112276D03*
X1096460Y1115125D03*
X1092742Y1113462D03*
X1134100Y1433300D03*
X1090818Y1531620D03*
X1092927Y1558887D03*
Y1555087D03*
X1095938Y1531620D03*
Y1535420D03*
X1090818D03*
X1096547Y1558887D03*
Y1555087D03*
X1139500Y-58500D03*
X1150000Y-63000D03*
X1146768Y-31238D03*
X1139808Y-31171D03*
X1149699Y-35153D03*
X1142293Y-37522D03*
X1181568Y55168D03*
X1181868Y50568D03*
Y45568D03*
X1181568Y60168D03*
X1178268Y64068D03*
X1183268D03*
X1184088Y101360D03*
X1184141Y96794D03*
X1178268Y85068D03*
Y69068D03*
Y89068D03*
X1183268Y85068D03*
Y69068D03*
Y89068D03*
X1178656Y104637D03*
X1176952Y93390D03*
X1177500Y153500D03*
X1140550Y179200D03*
X1142800Y174637D03*
X1140500Y171400D03*
X1182590Y254388D03*
X1171749Y259163D03*
X1175400Y258800D03*
X1174037Y281343D03*
X1176300Y284500D03*
X1180953Y284800D03*
X1185588Y285035D03*
X1173500Y397000D03*
X1156500Y467000D03*
X1166500Y635000D03*
X1156500Y619000D03*
X1176835Y618934D03*
X1156500Y650000D03*
X1169768Y730300D03*
Y723100D03*
Y726700D03*
X1175568Y712300D03*
X1171968D03*
X1175568Y715900D03*
X1171968D03*
X1173368Y730300D03*
X1171968Y719500D03*
X1175568D03*
X1173368Y726700D03*
Y723100D03*
X1181000Y814000D03*
X1156500Y813000D03*
X1179000Y829500D03*
X1166500D03*
X1138198Y832424D03*
X1158500Y868500D03*
X1172736Y1031786D03*
X1177036Y1032086D03*
X1144580Y1078680D03*
X1170140Y1043939D03*
X1172564Y1118373D03*
X1152880Y1097672D03*
X1152682Y1091138D03*
X1149984Y1115804D03*
X1143550Y1120317D03*
X1139524Y1121817D03*
X1152800Y1223062D03*
X1152700Y1216213D03*
X1150420Y1229800D03*
X1181400Y1266100D03*
X1184000Y1260100D03*
X1149823Y1233373D03*
X1144000Y1310000D03*
X1150232Y1316358D03*
X1154500Y1327500D03*
X1150911Y1329500D03*
X1228500Y12500D03*
X1204768Y64368D03*
X1199768D03*
X1209768D03*
X1204068Y50368D03*
Y45368D03*
X1203768Y60568D03*
Y55568D03*
X1188268Y64068D03*
X1224000Y104000D03*
X1199768Y69368D03*
X1204768D03*
X1209768D03*
X1204768Y85368D03*
X1199768D03*
X1209768D03*
Y89368D03*
X1199768D03*
X1204768D03*
X1188268Y85068D03*
Y69068D03*
Y89068D03*
X1215795Y181242D03*
X1186500Y220500D03*
X1224800Y225200D03*
X1219917Y239646D03*
X1215600Y261800D03*
X1219962Y244739D03*
X1194700Y261700D03*
X1189700Y308527D03*
X1190200Y285023D03*
X1201835Y305319D03*
X1193800Y307857D03*
X1198100Y306858D03*
X1197000Y279400D03*
X1226045Y431102D03*
X1232500Y541000D03*
X1197868Y730300D03*
X1194268D03*
Y723100D03*
Y726700D03*
X1197868Y723100D03*
Y726700D03*
X1192068Y712300D03*
X1195668D03*
X1192068Y715900D03*
X1195668D03*
Y719500D03*
X1192068D03*
X1188000Y753000D03*
X1192000Y869000D03*
X1232700Y950400D03*
X1194000Y1037900D03*
X1229691Y1148580D03*
X1232842Y1140722D03*
X1205303Y1227604D03*
X1240500Y20000D03*
X1254000Y105000D03*
X1281500Y103500D03*
X1278421Y205974D03*
X1281603Y203340D03*
X1282106Y180492D03*
X1280800Y167200D03*
X1282287Y243489D03*
X1277606Y217441D03*
X1282106Y235492D03*
X1248193Y242618D03*
X1255600Y237300D03*
X1250016Y247017D03*
X1253300Y227700D03*
X1273200Y263700D03*
X1276200Y277400D03*
X1262075Y297100D03*
X1250500Y266600D03*
X1280000Y430000D03*
X1235796Y517450D03*
X1250011Y516707D03*
X1239362Y524168D03*
X1253511Y517606D03*
X1264878Y508068D03*
X1282106Y648248D03*
Y633248D03*
Y618248D03*
X1253800Y689600D03*
X1277606Y670197D03*
X1282106Y688248D03*
X1277606Y660748D03*
Y651299D03*
X1282106Y728248D03*
Y718248D03*
Y698248D03*
X1268400Y716100D03*
X1265891Y699583D03*
X1263250Y823436D03*
X1243200Y933700D03*
X1259808Y927260D03*
X1250475Y969248D03*
X1271296Y986867D03*
X1274413Y984613D03*
X1279599Y976407D03*
X1253338Y980784D03*
X1253975Y970147D03*
X1264269Y981248D03*
X1263618Y990606D03*
X1268378Y990608D03*
X1239900Y1024000D03*
X1256142Y1029316D03*
X1279081Y1071085D03*
X1252400Y1054100D03*
X1277606Y1122953D03*
Y1113504D03*
Y1104055D03*
X1282106Y1101004D03*
Y1086004D03*
X1251250Y1141700D03*
X1282106Y1171004D03*
Y1151004D03*
Y1141004D03*
X1246557Y1148155D03*
X1249600Y1155800D03*
X1272755Y1137293D03*
X1260300Y1169000D03*
X1240314Y1139741D03*
X1268948Y1150173D03*
X1282106Y1181004D03*
X1254800Y1269600D03*
X1240276Y1356700D03*
X1319000Y12000D03*
X1309000Y45500D03*
X1318500Y34500D03*
X1323829Y55929D03*
X1328295Y55800D03*
X1319100Y78800D03*
X1323521Y79179D03*
X1312999Y107280D03*
X1317661Y107896D03*
X1299569Y84272D03*
X1304563Y84309D03*
Y100771D03*
X1299569Y100639D03*
X1312263Y95463D03*
X1315961Y98112D03*
X1289000Y145400D03*
X1314794Y162944D03*
X1324207Y138756D03*
X1315102Y137903D03*
X1302074Y183779D03*
X1311200Y172661D03*
X1304293Y165909D03*
X1315838Y188804D03*
X1297507Y195492D03*
X1330807Y181473D03*
X1311750Y187911D03*
X1326637Y226568D03*
X1316637D03*
X1321637D03*
X1298700Y272800D03*
X1298500Y302900D03*
X1305000Y299400D03*
X1313000Y302900D03*
X1313915Y263541D03*
X1289000Y309500D03*
X1311000Y321000D03*
X1303500Y434000D03*
X1287000Y456000D03*
X1310000Y597000D03*
X1289106Y594626D03*
X1303800Y636417D03*
X1311200Y625417D03*
X1307500Y615417D03*
X1315400Y648017D03*
X1326500Y627917D03*
X1311750Y640667D03*
X1312000Y615417D03*
X1318000Y680417D03*
X1323000D03*
X1328000D03*
X1302500Y718917D03*
X1314000Y717417D03*
X1298500Y752417D03*
X1305000D03*
X1313000D03*
X1289106Y766870D03*
X1316000Y772200D03*
X1310500Y774700D03*
X1312767Y885535D03*
X1286000Y982200D03*
X1284695Y956586D03*
X1305000Y1041500D03*
X1289114Y1048624D03*
X1311200Y1078173D03*
X1305100Y1068173D03*
X1326500Y1080673D03*
X1317400Y1068000D03*
X1309600Y1068173D03*
X1303800Y1089173D03*
X1315300Y1100773D03*
X1311750Y1093423D03*
X1302500Y1171673D03*
X1313950Y1165990D03*
X1328000Y1133173D03*
X1318000D03*
X1323000D03*
X1357500Y43500D03*
X1347500Y21000D03*
X1332500Y56500D03*
X1351200Y68600D03*
X1359350Y66350D03*
X1351201Y90099D03*
X1358355Y81488D03*
X1338215Y107586D03*
X1336034Y82542D03*
X1334383Y75892D03*
X1340961Y78811D03*
X1343521Y85472D03*
X1347607Y101337D03*
X1346081Y80671D03*
X1348641Y83326D03*
X1352351Y101724D03*
X1350779Y106496D03*
X1348641Y110550D03*
X1333281Y85133D03*
X1341922Y105649D03*
X1354500Y75400D03*
X1332934Y137712D03*
X1349931Y138361D03*
X1338400Y126015D03*
X1333988Y161471D03*
X1358971Y129978D03*
X1362685Y130109D03*
X1351665Y128325D03*
X1343112Y128997D03*
X1364017Y123277D03*
X1337662Y137188D03*
X1377463Y237100D03*
X1372274Y272874D03*
X1355991Y275272D03*
X1374338Y292900D03*
X1358573Y290900D03*
X1375700Y413400D03*
X1338000Y546500D03*
X1346363Y516578D03*
X1332148Y517321D03*
X1357316Y542311D03*
X1338100Y520300D03*
X1353500Y518900D03*
X1359882Y508014D03*
X1364882D03*
X1337500Y576500D03*
X1355700Y587600D03*
X1359700D03*
X1372272Y573560D03*
X1336000Y627000D03*
X1375463Y689917D03*
X1373553Y700994D03*
X1347600Y734078D03*
X1344062Y737800D03*
X1339500Y794000D03*
X1354500Y747304D03*
X1360920Y749829D03*
X1334300Y771200D03*
X1338729Y776131D03*
X1338700Y771500D03*
X1334329Y775831D03*
X1373519Y761900D03*
X1341219Y933282D03*
X1346080Y907004D03*
X1344000Y987500D03*
X1362000Y987000D03*
X1331070Y966090D03*
X1348796Y969488D03*
X1378100Y972100D03*
X1339404Y969600D03*
X1353762Y969886D03*
X1349829Y1014840D03*
X1365551Y1028250D03*
X1368935Y1123365D03*
X1361074Y1114565D03*
X1365461Y1136100D03*
X1375463Y1142673D03*
X1364713Y1143791D03*
X1360238Y1143867D03*
X1370716Y1148037D03*
X1355733Y1241900D03*
X1369600Y1330100D03*
X1373700Y1330000D03*
X1365551Y1353500D03*
X1413268Y146062D03*
X1401819Y207992D03*
X1394705Y195413D03*
X1406319Y180492D03*
X1405100Y166000D03*
X1427663Y167032D03*
X1403963Y245492D03*
X1385051Y218684D03*
X1406000Y236700D03*
X1384475Y255839D03*
X1426713Y266161D03*
X1406319Y275492D03*
Y265492D03*
X1384713Y323200D03*
X1414882Y397271D03*
X1395300Y438500D03*
X1418225Y421700D03*
X1418493Y531407D03*
X1425600Y544600D03*
X1418507Y517007D03*
X1407936Y552099D03*
Y548099D03*
X1425200Y540100D03*
X1414319Y523900D03*
X1396297Y573397D03*
X1421239Y558029D03*
X1396297Y579803D03*
X1421239Y562229D03*
X1421500Y664000D03*
X1401819Y670197D03*
X1406319Y688248D03*
X1401819Y660748D03*
X1426713Y718917D03*
X1406319Y728248D03*
Y718248D03*
Y698248D03*
X1383952Y717435D03*
X1422713Y752417D03*
X1398245Y766870D03*
X1395000Y791500D03*
X1392355Y886696D03*
X1391000Y932400D03*
X1380300Y930200D03*
X1390000Y955500D03*
X1384800Y1002666D03*
X1390500Y1048000D03*
X1406319Y1071004D03*
X1413319Y1047382D03*
X1406319Y1086004D03*
Y1101004D03*
X1401819Y1104055D03*
X1385494Y1113504D03*
X1401819Y1122953D03*
X1406319Y1141004D03*
Y1151004D03*
Y1171004D03*
X1426713Y1171673D03*
X1383899Y1166690D03*
X1406319Y1181004D03*
X1388500Y1224900D03*
X1381800Y1329600D03*
X1431713Y162661D03*
X1463804Y138605D03*
X1436204Y159247D03*
X1428013Y185956D03*
X1445994Y174086D03*
X1440300Y188000D03*
X1435963Y183833D03*
X1450713Y173049D03*
X1456373Y168971D03*
X1438186Y261287D03*
X1442213Y227661D03*
X1447213D03*
X1452213D03*
X1444238Y349852D03*
X1439654D03*
X1431909Y359311D03*
X1463000Y490638D03*
X1457200Y549600D03*
X1470700Y522100D03*
X1456439Y515000D03*
X1448261D03*
X1435200D03*
X1443700D03*
X1460200D03*
X1452200D03*
X1465700D03*
X1439200D03*
X1442500Y548400D03*
X1456450Y529600D03*
X1448450D03*
X1459200Y579600D03*
X1452200D03*
X1442500Y554700D03*
X1455750Y572350D03*
X1474700Y569100D03*
X1447700Y579600D03*
X1474700Y579100D03*
X1450713Y627817D03*
X1435963Y640667D03*
X1455202Y618557D03*
X1436213Y615417D03*
X1442213Y680417D03*
X1447213D03*
X1452213D03*
X1449000Y698000D03*
X1438087Y713756D03*
X1429213Y752417D03*
X1437213D03*
X1474083Y764750D03*
X1471608Y768500D03*
X1432000Y831000D03*
X1459500Y814000D03*
X1450500Y802500D03*
X1459500Y796500D03*
X1473000Y798000D03*
X1433500Y864500D03*
X1435300Y882700D03*
X1440500Y893500D03*
X1448000Y910000D03*
X1457500Y987500D03*
X1440000Y986500D03*
X1473008Y969646D03*
X1458967Y969535D03*
X1463616Y969265D03*
X1451800Y1004700D03*
X1433500Y1044000D03*
X1456000D03*
X1435413Y1078173D03*
X1431713Y1068173D03*
X1450713Y1080673D03*
X1446213Y1062300D03*
X1436213Y1068173D03*
X1428013Y1089173D03*
X1439713Y1100773D03*
X1442213Y1132173D03*
X1447213D03*
X1452213D03*
X1439750Y1096673D03*
X1438213Y1170173D03*
X1467000Y1221800D03*
X1473600Y1242777D03*
X1511177Y125412D03*
X1498900Y235800D03*
X1499775Y248061D03*
X1508925Y323200D03*
X1481938Y489926D03*
X1485932Y522335D03*
X1500600Y523300D03*
X1502400Y544100D03*
X1497849Y545264D03*
X1486594Y508098D03*
X1491594D03*
X1513200Y519700D03*
X1509800Y516100D03*
X1494400Y560400D03*
Y556100D03*
X1494462Y692179D03*
X1500539Y739639D03*
X1498000Y743000D03*
X1505900Y717600D03*
X1495480Y704558D03*
X1489000Y723000D03*
X1515000Y789000D03*
X1520000Y776000D03*
X1499500Y774000D03*
X1476558Y759088D03*
X1479033Y762259D03*
X1486600Y786559D03*
X1499500Y831000D03*
X1510500Y878000D03*
X1510000Y860500D03*
X1505900Y930400D03*
X1521200Y928000D03*
X1512500Y949000D03*
X1503394Y968179D03*
X1477974Y970044D03*
X1508500Y1028500D03*
X1484000Y992315D03*
X1481500Y995758D03*
X1478194Y1017166D03*
X1481529Y1030500D03*
X1508500Y1050500D03*
X1488500Y1096000D03*
X1489096Y1131456D03*
X1489108Y1121674D03*
X1485608Y1113628D03*
X1499675Y1142673D03*
X1489333Y1147664D03*
X1504200Y1171300D03*
X1485833Y1140369D03*
X1495900Y1149000D03*
X1491662Y1351300D03*
X1494662Y1336000D03*
X1497200Y1342500D03*
X1501600Y1342300D03*
X1560425Y162661D03*
X1563925Y195261D03*
X1526031Y207992D03*
Y198543D03*
X1560175Y187911D03*
X1530531Y245492D03*
X1526031Y217441D03*
X1530142Y238021D03*
X1566425Y227661D03*
X1571425D03*
X1550925Y266161D03*
X1562425Y264661D03*
X1530531Y275492D03*
Y265492D03*
X1568500Y438500D03*
Y544100D03*
X1568000Y548500D03*
X1530531Y648248D03*
X1555175Y642667D03*
X1560425Y615417D03*
X1558925Y650017D03*
X1526031Y670197D03*
X1530531Y688248D03*
X1526031Y660748D03*
Y651299D03*
X1566425Y677417D03*
X1571425D03*
X1550925Y718917D03*
X1562425Y717417D03*
X1530531Y728248D03*
Y718248D03*
Y698248D03*
X1526000Y728000D03*
X1555000Y770000D03*
X1546925Y752417D03*
X1553425D03*
X1561425D03*
X1537531Y766870D03*
X1525000Y878000D03*
X1570500Y888400D03*
X1564500Y931000D03*
X1548500Y933000D03*
X1564000Y949000D03*
X1552500Y1028000D03*
X1557500Y1043500D03*
X1537531Y1047382D03*
X1559625Y1078173D03*
X1555925Y1068173D03*
X1530531Y1071004D03*
X1570425Y1062000D03*
X1560425Y1068173D03*
X1552225Y1089173D03*
X1526031Y1122953D03*
Y1113504D03*
Y1104055D03*
X1530531Y1101004D03*
Y1086004D03*
X1550925Y1171673D03*
X1552575Y1139700D03*
X1562425Y1170173D03*
X1530531Y1171004D03*
Y1151004D03*
X1528723Y1138918D03*
X1556231Y1134920D03*
X1530531Y1181004D03*
X1558650Y1217426D03*
X1607000Y199000D03*
X1574925Y175061D03*
X1579371Y166019D03*
X1595500Y258500D03*
X1621100Y240561D03*
X1608000Y256000D03*
X1576425Y227661D03*
X1621100Y244661D03*
X1620000Y340000D03*
Y320000D03*
X1586596Y518723D03*
X1600745Y517561D03*
X1574925Y627817D03*
X1578926Y618657D03*
X1576425Y677417D03*
X1620469Y697517D03*
X1580000Y780000D03*
X1576500Y928500D03*
X1584800Y895800D03*
X1587400Y912200D03*
X1608200Y914400D03*
X1618200Y916800D03*
X1597221Y969572D03*
X1583180Y969461D03*
X1574576Y976700D03*
X1615494Y973179D03*
X1587829Y969191D03*
X1602187Y969970D03*
X1596000Y990000D03*
X1580381Y1007066D03*
X1602400Y1019366D03*
X1620059Y1032932D03*
X1611500Y1078000D03*
X1593000Y1043500D03*
X1574925Y1080673D03*
X1603425Y1105040D03*
Y1100040D03*
X1598425Y1102440D03*
Y1107440D03*
X1620059Y1128071D03*
X1593500Y1185500D03*
X1613400Y1236500D03*
X1650244Y207992D03*
Y198543D03*
X1654744Y195492D03*
Y180492D03*
Y165492D03*
Y245492D03*
X1650244Y217441D03*
X1654744Y235492D03*
X1652387Y277343D03*
X1653789Y267766D03*
X1622738Y264938D03*
X1639000Y320000D03*
X1640000Y340000D03*
X1660000D03*
X1661744Y314114D03*
X1660000Y400000D03*
X1640000Y360000D03*
X1660000Y440000D03*
Y480000D03*
X1640000D03*
Y460000D03*
X1660000D03*
X1640000Y500000D03*
X1660000D03*
X1621138Y719238D03*
X1643344Y887455D03*
X1646013Y884255D03*
X1639644Y889755D03*
X1633600Y936300D03*
X1621787Y917108D03*
X1636400Y925800D03*
X1650000Y980000D03*
X1629094Y975179D03*
X1653500Y1016500D03*
X1650000Y1000000D03*
X1632000Y1049500D03*
X1654744Y1071004D03*
X1661744Y1047382D03*
X1650244Y1122953D03*
Y1113504D03*
Y1104055D03*
X1654744Y1101004D03*
Y1086004D03*
X1627563Y1132075D03*
X1627802Y1118949D03*
X1627769Y1110037D03*
X1624198Y1111309D03*
X1635688Y1141158D03*
X1650841Y1168660D03*
X1654744Y1151004D03*
Y1141004D03*
X1627197Y1143044D03*
X1633138Y1165673D03*
X1635688Y1153773D03*
X1668378Y1181004D03*
X1624500Y1349100D03*
X1680138Y162661D03*
X1684638D03*
X1676438Y183661D03*
X1683838Y172661D03*
X1688138Y195261D03*
X1684388Y187911D03*
X1699138Y175061D03*
X1703584Y166019D03*
X1690638Y227661D03*
X1695638D03*
X1700638D03*
X1675475Y267424D03*
X1671138Y299661D03*
X1677638D03*
X1685638D03*
X1686638Y264661D03*
X1678500Y320000D03*
X1700000Y400000D03*
X1680000Y380000D03*
X1700000Y360000D03*
X1680000Y440000D03*
Y420000D03*
X1700000Y440000D03*
Y420000D03*
Y460000D03*
X1680000Y480000D03*
Y460000D03*
Y500000D03*
X1707495Y517152D03*
X1711061Y518470D03*
X1684388Y638324D03*
X1699138Y627917D03*
X1705000Y618667D03*
X1684638Y615417D03*
X1699638Y675417D03*
X1689638D03*
X1694638D03*
X1692100Y923600D03*
X1704010Y898000D03*
X1674814Y961977D03*
X1677056Y954636D03*
X1680012Y952402D03*
X1706000Y1022000D03*
X1717681Y1006054D03*
X1712181Y1001554D03*
X1685047Y1014966D03*
X1680087Y1023983D03*
X1671422Y1009266D03*
X1690279Y1011526D03*
X1691771Y1035163D03*
X1683838Y1078173D03*
X1680138Y1068173D03*
X1699138Y1080573D03*
X1685100Y1054000D03*
X1679300Y1043169D03*
X1694638Y1063600D03*
X1684638Y1068173D03*
X1688138Y1100773D03*
X1676438Y1089173D03*
X1700638Y1131673D03*
X1695638D03*
X1690638D03*
X1684388Y1091723D03*
X1686638Y1170173D03*
X1675138Y1171673D03*
X1702838Y1215300D03*
X1710617Y1231429D03*
X1715049Y1234000D03*
X1728500Y249500D03*
X1746600Y240561D03*
X1760486Y217441D03*
X1746400Y244561D03*
X1763500Y288000D03*
X1720000Y300000D03*
Y280000D03*
X1747550Y265000D03*
X1720000Y340000D03*
X1760000D03*
X1740000Y320000D03*
X1760000Y440000D03*
Y420000D03*
Y500000D03*
Y480000D03*
Y460000D03*
X1740000Y540000D03*
X1760000D03*
Y520000D03*
X1721710Y516409D03*
X1725100Y519300D03*
X1745000Y670000D03*
Y690000D03*
Y660000D03*
X1730000Y690000D03*
Y670000D03*
Y730000D03*
Y710000D03*
Y750000D03*
X1752000Y929200D03*
X1759884Y969161D03*
X1757600Y987200D03*
X1761600D03*
Y983200D03*
X1757600D03*
X1742001Y965464D03*
X1755010Y966285D03*
X1738863Y985225D03*
X1761600Y991200D03*
Y999200D03*
Y995200D03*
X1757600Y991200D03*
X1753600Y995200D03*
Y999200D03*
X1757600D03*
Y995200D03*
X1726681Y1001554D03*
X1719681D03*
X1722181Y1009054D03*
X1763714Y1015491D03*
X1755900Y1014600D03*
X1740499Y1008223D03*
X1749863Y1003925D03*
X1756100Y1004362D03*
X1746030Y1004209D03*
X1737241Y997843D03*
X1740363Y989225D03*
X1755000Y1045000D03*
X1725000D03*
X1745000Y1100000D03*
X1759055Y1113504D03*
X1736725Y1123446D03*
X1733245Y1115503D03*
X1748100Y1142673D03*
X1736871Y1158178D03*
X1736941Y1141871D03*
X1751400Y1173900D03*
X1732768Y1141697D03*
X1748100Y1153673D03*
X1755900Y1212704D03*
X1740000Y1346900D03*
X1804350Y162661D03*
X1808850D03*
X1801988Y183904D03*
X1808050Y172661D03*
X1812350Y195261D03*
X1774456Y207992D03*
Y198543D03*
X1778956Y195492D03*
Y180492D03*
X1775140Y165728D03*
X1808600Y187911D03*
X1778956Y245492D03*
Y235492D03*
X1799350Y266161D03*
X1795350Y299661D03*
X1801850D03*
X1809850D03*
X1810850Y264661D03*
X1778956Y275492D03*
Y265492D03*
X1785956Y314114D03*
X1800000Y440000D03*
X1780000D03*
X1800000Y500000D03*
X1780000D03*
X1800000Y480000D03*
Y460000D03*
X1780000Y480000D03*
Y460000D03*
X1800000Y540000D03*
X1780000D03*
X1800000Y520000D03*
X1780000D03*
X1800000Y560000D03*
X1785956Y594626D03*
X1800650Y636417D03*
X1808050Y625417D03*
X1804350Y615417D03*
X1812350Y648017D03*
X1778956Y648248D03*
Y633248D03*
Y618248D03*
X1808600Y640667D03*
X1808850Y615417D03*
X1774456Y670197D03*
X1778956Y688248D03*
X1774456Y660748D03*
Y651299D03*
X1799326Y717506D03*
X1811474Y717423D03*
X1778956Y728248D03*
Y718248D03*
Y698248D03*
X1766721Y716500D03*
Y720500D03*
X1795468Y752594D03*
X1801968D03*
X1809968D03*
X1785956Y766870D03*
X1813851Y927406D03*
X1788361Y964676D03*
X1799051Y963346D03*
X1768692Y966073D03*
X1797463Y968652D03*
X1806077Y961860D03*
X1783778Y970371D03*
X1774863Y1024725D03*
X1788726Y1034726D03*
X1778863Y1005725D03*
X1787163Y1009741D03*
X1772863Y1005304D03*
X1778963Y999125D03*
X1772263Y995925D03*
X1785956Y1047382D03*
X1808050Y1078173D03*
X1800750Y1067973D03*
X1778956Y1071004D03*
X1812050Y1071223D03*
X1805250Y1067973D03*
X1800650Y1089173D03*
X1811968Y1100773D03*
X1774456Y1122953D03*
Y1104055D03*
X1778956Y1101004D03*
Y1086004D03*
X1799350Y1171673D03*
X1810850Y1170173D03*
X1778956Y1171004D03*
Y1151004D03*
Y1141004D03*
Y1181004D03*
X1859017Y161725D03*
X1841021Y152968D03*
X1845517Y158475D03*
X1859117Y167375D03*
X1851717Y179075D03*
X1856219Y212661D03*
Y201661D03*
X1823350Y175161D03*
X1827796Y166019D03*
X1841169Y254661D03*
X1850669Y219661D03*
X1846169D03*
X1841669D03*
X1824850Y227661D03*
X1819850D03*
X1814850D03*
X1840000Y340000D03*
Y320000D03*
X1860000D03*
X1820000D03*
Y440000D03*
Y480000D03*
Y460000D03*
X1840000Y540000D03*
X1820000D03*
X1845545Y516536D03*
X1831330Y517279D03*
X1834896Y518597D03*
X1849045Y517435D03*
X1840000Y580000D03*
X1820000D03*
X1840000Y560000D03*
X1820000D03*
X1858917Y614481D03*
X1859117Y620131D03*
X1851717Y635331D03*
X1823350Y627917D03*
X1827667Y618703D03*
X1840855Y606200D03*
X1845417Y611231D03*
X1862200Y686700D03*
X1856219Y665417D03*
X1841669Y672417D03*
X1846169D03*
X1850669D03*
X1814850Y680417D03*
X1819850D03*
X1824850D03*
X1856219Y654417D03*
X1850000Y745000D03*
X1837576Y707417D03*
X1820000Y780000D03*
X1848491Y819787D03*
Y823787D03*
Y815787D03*
Y807787D03*
X1850151Y835119D03*
X1850177Y838746D03*
X1838239Y831626D03*
X1845579Y831731D03*
X1838311Y827911D03*
X1845651Y828016D03*
X1848491Y811787D03*
X1855676Y800787D03*
X1824170Y886349D03*
X1819541Y921500D03*
X1823937Y890883D03*
X1821152Y907899D03*
X1825971Y1015512D03*
Y1010012D03*
X1840445Y1015620D03*
Y1010120D03*
X1835895Y1020064D03*
X1830395D03*
X1857363Y1002625D03*
X1845363D03*
X1849363D03*
X1861363D03*
X1853363D03*
X1823350Y1080673D03*
X1856437Y1106400D03*
X1858046Y1092779D03*
X1836953Y1103391D03*
X1850363Y1115037D03*
X1847506Y1118794D03*
X1851565Y1118784D03*
X1850280Y1111373D03*
X1816046Y1098532D03*
X1836200Y1130000D03*
X1850532Y1153286D03*
X1836231Y1140669D03*
X1824850Y1133173D03*
X1814850D03*
X1819850D03*
X1840585Y1151653D03*
X1842000Y1344700D03*
X1869500Y179134D03*
X1876938Y181062D03*
X1873500Y219000D03*
X1865169Y247161D03*
Y234661D03*
X1881088Y296184D03*
X1880969Y276861D03*
X1880000Y340000D03*
Y320000D03*
X1890000Y440000D03*
X1910169Y594626D03*
X1903169Y648248D03*
Y633248D03*
Y618248D03*
X1885300Y636800D03*
X1869500Y633500D03*
X1878900Y637000D03*
X1898669Y670197D03*
X1903169Y688248D03*
X1898669Y660748D03*
Y651299D03*
X1903169Y728248D03*
Y718248D03*
Y698248D03*
X1880969Y729617D03*
X1865169Y699917D03*
X1880000Y780000D03*
X1910169Y766870D03*
X1887169Y752917D03*
X1908107Y831894D03*
X1902607D03*
X1907999Y846368D03*
X1902499D03*
X1884800Y890750D03*
X1902441Y888500D03*
X1896943Y894350D03*
X1891676Y917759D03*
X1884500Y912500D03*
X1904000Y933500D03*
Y929000D03*
Y925000D03*
X1906500Y893400D03*
X1909358Y897500D03*
X1904000Y938000D03*
X1873001Y901396D03*
X1904000Y921000D03*
X1872190Y936766D03*
X1865363Y1002625D03*
X1867963Y996425D03*
X1868100Y1055410D03*
X1871000Y1073300D03*
X1884835Y1067400D03*
X1887402Y1050193D03*
X1872162Y1055426D03*
X1864617Y1040934D03*
X1888085Y1059938D03*
X1876662Y1055426D03*
X1863700Y1085000D03*
X1873500Y1329000D03*
X1912551Y836444D03*
Y841944D03*
X1911676Y893469D03*
G54D31*
X429724Y63977D03*
Y68307D03*
X443898Y63977D03*
X458071D03*
Y68307D03*
X443898D03*
X429724Y116339D03*
Y96654D03*
Y102166D03*
Y110827D03*
Y87993D03*
Y82481D03*
Y73819D03*
X443898Y116339D03*
X458071D03*
X436811Y114764D03*
X450984D03*
X443898Y96654D03*
X458071D03*
X443898Y102166D03*
X458071D03*
X436811Y100591D03*
X450984D03*
X436811Y106103D03*
X450984D03*
X443898Y110827D03*
X458071D03*
Y87993D03*
Y82481D03*
X450984Y91930D03*
Y86418D03*
X443898Y87993D03*
Y82481D03*
X436811Y91930D03*
Y86418D03*
X458071Y73819D03*
X450984Y77756D03*
Y72245D03*
X443898Y73819D03*
X436811Y77756D03*
Y72245D03*
Y120276D03*
X450984D03*
X472244Y63977D03*
Y68307D03*
X465157Y114764D03*
X472244Y116339D03*
X479331Y114764D03*
X465157Y100591D03*
Y106103D03*
X472244Y96654D03*
Y102166D03*
X479331Y100591D03*
Y106103D03*
X472244Y110827D03*
X479331Y91930D03*
Y86418D03*
X472244Y87993D03*
Y82481D03*
X465157Y91930D03*
Y86418D03*
X479331Y77756D03*
Y72245D03*
X472244Y73819D03*
X465157Y77756D03*
Y72245D03*
Y120276D03*
X479331D03*
X514764Y63977D03*
Y68307D03*
X543110Y63977D03*
X528937D03*
X543110Y68307D03*
X528937D03*
X557283Y63977D03*
Y68307D03*
X514764Y116339D03*
Y110827D03*
Y102166D03*
Y96654D03*
Y87993D03*
Y82481D03*
Y73819D03*
X550197Y114764D03*
X536024D03*
X521850D03*
X543110Y116339D03*
X528937D03*
X543110Y110827D03*
X528937D03*
X550197Y106103D03*
X536024D03*
X521850D03*
X550197Y100591D03*
X536024D03*
X521850D03*
X543110Y102166D03*
X528937D03*
X543110Y96654D03*
X528937D03*
X550197Y91930D03*
Y86418D03*
X543110Y87993D03*
Y82481D03*
X536024Y91930D03*
Y86418D03*
X528937Y87993D03*
Y82481D03*
X521850Y91930D03*
Y86418D03*
X550197Y77756D03*
Y72245D03*
X543110Y73819D03*
X536024Y77756D03*
Y72245D03*
X528937Y73819D03*
X521850Y77756D03*
Y72245D03*
X557283Y116339D03*
Y110827D03*
Y102166D03*
Y96654D03*
Y87993D03*
Y82481D03*
Y73819D03*
X550197Y120276D03*
X536024D03*
X521850D03*
X564370Y114764D03*
Y106103D03*
Y100591D03*
Y91930D03*
Y86418D03*
Y77756D03*
Y72245D03*
Y120276D03*
X833859Y1598425D03*
Y1603937D03*
Y1612599D03*
X840945Y1602363D03*
X826772D03*
X840945Y1607874D03*
X826772D03*
X840945Y1616536D03*
X826772D03*
X833859Y1618111D03*
Y1626772D03*
Y1632284D03*
Y1640945D03*
Y1646457D03*
X840945Y1622048D03*
X826772D03*
X840945Y1630709D03*
X826772D03*
X840945Y1636221D03*
X826772D03*
X840945Y1644882D03*
X826772D03*
X840945Y1650394D03*
X826772D03*
X876378Y1598425D03*
X862205D03*
X848032D03*
X876378Y1603937D03*
X862205D03*
X848032D03*
X876378Y1612599D03*
X862205D03*
X848032D03*
X890552Y1602363D03*
X869292D03*
X855118D03*
X890552Y1607874D03*
X869292D03*
X855118D03*
X890552Y1612205D03*
Y1616536D03*
X869292D03*
X855118D03*
X876378Y1618111D03*
X862205D03*
X848032D03*
X876378Y1626772D03*
X862205D03*
X848032D03*
X876378Y1632284D03*
X862205D03*
X848032D03*
X876378Y1640945D03*
X862205D03*
X848032D03*
X876378Y1646457D03*
X862205D03*
X848032D03*
X890552Y1622048D03*
X869292D03*
X855118D03*
X890552Y1626378D03*
Y1630709D03*
X869292D03*
X855118D03*
X890552Y1636221D03*
X869292D03*
X855118D03*
X890552Y1640551D03*
Y1644882D03*
X869292D03*
X855118D03*
X890552Y1650394D03*
X869292D03*
X855118D03*
X911811Y1603937D03*
Y1608268D03*
Y1612599D03*
X904725Y1602363D03*
Y1607874D03*
Y1612205D03*
Y1616536D03*
Y1598032D03*
X897638Y1598425D03*
Y1603937D03*
Y1608268D03*
Y1612599D03*
X911811Y1632284D03*
Y1636614D03*
Y1640945D03*
Y1646457D03*
Y1650788D03*
X904725Y1630709D03*
Y1636221D03*
Y1640551D03*
Y1644882D03*
Y1650394D03*
X911811Y1618111D03*
Y1622441D03*
Y1626772D03*
X904725Y1622048D03*
Y1626378D03*
X897638Y1618111D03*
Y1622441D03*
Y1626772D03*
Y1632284D03*
Y1636614D03*
Y1640945D03*
Y1646457D03*
Y1650788D03*
X1095420Y988592D03*
X1100932D03*
X1109593D03*
X1115105D03*
X1123766D03*
X1129278D03*
X1099357Y995678D03*
X1104869D03*
X1113530D03*
X1119042D03*
X1127703D03*
X1133215D03*
X1095420Y1002765D03*
X1100932D03*
X1109593D03*
X1115105D03*
X1123766D03*
X1129278D03*
X1099357Y1009852D03*
X1104869D03*
X1113530D03*
X1119042D03*
X1127703D03*
X1133215D03*
X1095420Y1016938D03*
X1100932D03*
X1109593D03*
X1115105D03*
X1123766D03*
X1129278D03*
X1099357Y1024025D03*
X1104869D03*
X1113530D03*
X1119042D03*
X1127703D03*
X1133215D03*
X1095420Y1031111D03*
X1100932D03*
X1109593D03*
X1115105D03*
X1123766D03*
X1129278D03*
X1099357Y1038198D03*
X1104869D03*
X1113530D03*
X1119042D03*
X1127703D03*
X1133215D03*
X1095420Y1160257D03*
Y1174430D03*
X1100932Y1160257D03*
Y1174430D03*
X1109593Y1160257D03*
Y1174430D03*
X1115105Y1160257D03*
Y1174430D03*
X1123766Y1160257D03*
Y1174430D03*
X1129278Y1160257D03*
Y1174430D03*
X1099357Y1167343D03*
X1104869D03*
X1113530D03*
X1119042D03*
X1127703D03*
X1133215D03*
X1095420Y1188603D03*
Y1202776D03*
Y1216949D03*
X1100932Y1188603D03*
Y1202776D03*
Y1216949D03*
X1109593Y1188603D03*
Y1202776D03*
Y1216949D03*
X1115105Y1188603D03*
Y1202776D03*
Y1216949D03*
X1123766Y1188603D03*
Y1202776D03*
Y1216949D03*
X1129278Y1188603D03*
Y1202776D03*
Y1216949D03*
X1099357Y1181516D03*
Y1195690D03*
Y1209863D03*
Y1224036D03*
X1104869Y1181516D03*
Y1195690D03*
Y1209863D03*
Y1224036D03*
X1113530Y1181516D03*
Y1195690D03*
Y1209863D03*
Y1224036D03*
X1119042Y1181516D03*
Y1195690D03*
Y1209863D03*
Y1224036D03*
X1127703Y1181516D03*
Y1195690D03*
Y1209863D03*
Y1224036D03*
X1133215Y1181516D03*
Y1195690D03*
Y1209863D03*
Y1224036D03*
X1095420Y1231123D03*
Y1245296D03*
Y1259469D03*
Y1273642D03*
X1100932Y1231123D03*
Y1245296D03*
Y1259469D03*
Y1273642D03*
X1109593Y1231123D03*
Y1245296D03*
Y1259469D03*
Y1273642D03*
X1115105Y1231123D03*
Y1245296D03*
Y1259469D03*
Y1273642D03*
X1123766Y1231123D03*
Y1245296D03*
Y1259469D03*
Y1273642D03*
X1129278Y1231123D03*
Y1245296D03*
Y1259469D03*
Y1273642D03*
X1099357Y1238209D03*
Y1252382D03*
Y1266556D03*
X1104869Y1238209D03*
Y1252382D03*
Y1266556D03*
X1113530Y1238209D03*
Y1252382D03*
Y1266556D03*
X1119042Y1238209D03*
Y1252382D03*
Y1266556D03*
X1127703Y1238209D03*
Y1252382D03*
Y1266556D03*
X1133215Y1238209D03*
Y1252382D03*
Y1266556D03*
X1095420Y1287816D03*
Y1301989D03*
Y1316162D03*
X1100932Y1287816D03*
Y1301989D03*
Y1316162D03*
X1109593Y1287816D03*
Y1301989D03*
Y1316162D03*
X1115105Y1287816D03*
Y1301989D03*
Y1316162D03*
X1123766Y1287816D03*
Y1301989D03*
Y1316162D03*
X1129278Y1287816D03*
Y1301989D03*
Y1316162D03*
X1099357Y1280729D03*
Y1294902D03*
Y1309075D03*
Y1323249D03*
X1104869Y1280729D03*
Y1294902D03*
Y1309075D03*
Y1323249D03*
X1113530Y1280729D03*
Y1294902D03*
Y1309075D03*
Y1323249D03*
X1119042Y1280729D03*
Y1294902D03*
Y1309075D03*
Y1323249D03*
X1127703Y1280729D03*
Y1294902D03*
Y1309075D03*
Y1323249D03*
X1133215Y1280729D03*
Y1294902D03*
Y1309075D03*
Y1323249D03*
X1095420Y1330335D03*
Y1344508D03*
Y1358682D03*
Y1372855D03*
X1100932Y1330335D03*
Y1344508D03*
Y1358682D03*
Y1372855D03*
X1109593Y1330335D03*
Y1344508D03*
Y1358682D03*
Y1372855D03*
X1115105Y1330335D03*
Y1344508D03*
Y1358682D03*
Y1372855D03*
X1123766Y1330335D03*
Y1344508D03*
Y1358682D03*
Y1372855D03*
X1129278Y1330335D03*
Y1344508D03*
Y1358682D03*
Y1372855D03*
X1099357Y1337422D03*
Y1351595D03*
Y1365768D03*
X1104869Y1337422D03*
Y1351595D03*
Y1365768D03*
X1113530Y1337422D03*
Y1351595D03*
Y1365768D03*
X1119042Y1337422D03*
Y1351595D03*
Y1365768D03*
X1127703Y1337422D03*
Y1351595D03*
Y1365768D03*
X1133215Y1337422D03*
Y1351595D03*
Y1365768D03*
X1095420Y1387028D03*
Y1401201D03*
X1100932Y1387028D03*
Y1401201D03*
X1109593Y1387028D03*
Y1401201D03*
X1115105Y1387028D03*
Y1401201D03*
X1123766Y1387028D03*
Y1401201D03*
X1129278Y1387028D03*
Y1401201D03*
X1099357Y1379942D03*
Y1394115D03*
Y1408288D03*
X1104869Y1379942D03*
Y1394115D03*
Y1408288D03*
X1113530Y1379942D03*
Y1394115D03*
Y1408288D03*
X1119042Y1379942D03*
Y1394115D03*
Y1408288D03*
X1127703Y1379942D03*
Y1394115D03*
Y1408288D03*
X1133215Y1379942D03*
Y1394115D03*
Y1408288D03*
X1398228Y63977D03*
Y68307D03*
X1412402Y63977D03*
X1426575D03*
Y68307D03*
X1412402D03*
X1398228Y116339D03*
Y96654D03*
Y102166D03*
Y110827D03*
Y87993D03*
Y82481D03*
Y73819D03*
X1412402Y116339D03*
X1426575D03*
X1405315Y114764D03*
X1419488D03*
X1412402Y96654D03*
X1426575D03*
X1412402Y102166D03*
X1426575D03*
X1405315Y100591D03*
X1419488D03*
X1405315Y106103D03*
X1419488D03*
X1412402Y110827D03*
X1426575D03*
Y87993D03*
Y82481D03*
X1419488Y91930D03*
Y86418D03*
X1412402Y87993D03*
Y82481D03*
X1405315Y91930D03*
Y86418D03*
X1426575Y73819D03*
X1419488Y77756D03*
Y72245D03*
X1412402Y73819D03*
X1405315Y77756D03*
Y72245D03*
Y120276D03*
X1419488D03*
X1440748Y63977D03*
Y68307D03*
X1433661Y114764D03*
X1440748Y116339D03*
X1447835Y114764D03*
X1433661Y100591D03*
Y106103D03*
X1440748Y96654D03*
Y102166D03*
X1447835Y100591D03*
Y106103D03*
X1440748Y110827D03*
X1447835Y91930D03*
Y86418D03*
X1440748Y87993D03*
Y82481D03*
X1433661Y91930D03*
Y86418D03*
X1447835Y77756D03*
Y72245D03*
X1440748Y73819D03*
X1433661Y77756D03*
Y72245D03*
Y120276D03*
X1447835D03*
X1483268Y63977D03*
Y68307D03*
X1511614Y63977D03*
X1497441D03*
X1511614Y68307D03*
X1497441D03*
X1483268Y106496D03*
Y92323D03*
Y87993D03*
Y82481D03*
Y73819D03*
X1518701Y114764D03*
X1504528D03*
X1490354D03*
X1511614Y116339D03*
X1497441D03*
X1490354Y110433D03*
X1511614Y110827D03*
X1497441D03*
X1518701Y106103D03*
X1504528D03*
X1490354D03*
X1497441Y106496D03*
X1518701Y100591D03*
X1504528D03*
X1490354D03*
X1511614Y102166D03*
X1497441D03*
X1490354Y96260D03*
X1511614Y96654D03*
X1497441D03*
X1518701Y91930D03*
Y86418D03*
X1511614Y87993D03*
Y82481D03*
X1504528Y91930D03*
Y86418D03*
X1497441Y87993D03*
Y82481D03*
X1490354Y91930D03*
Y86418D03*
X1518701Y77756D03*
Y72245D03*
X1511614Y73819D03*
X1504528Y77756D03*
Y72245D03*
X1497441Y73819D03*
X1490354Y77756D03*
Y72245D03*
X1483268Y120670D03*
X1518701Y120276D03*
X1504528D03*
X1497441Y120670D03*
X1525787Y63977D03*
Y68307D03*
X1532874Y114764D03*
X1525787Y116339D03*
Y110827D03*
X1532874Y106103D03*
Y100591D03*
X1525787Y102166D03*
Y96654D03*
X1532874Y91930D03*
Y86418D03*
X1525787Y87993D03*
Y82481D03*
X1532874Y77756D03*
Y72245D03*
X1525787Y73819D03*
X1532874Y120276D03*
G54D42*
X988795Y1571058D03*
Y1576658D03*
X1026106Y1545595D03*
Y1539995D03*
X1031706Y1545595D03*
Y1539995D03*
X1020574Y1540059D03*
Y1545659D03*
X1039758Y1559605D03*
X1014974Y1540059D03*
Y1545659D03*
X1039358Y1565405D03*
X1033717Y1563634D03*
X1028223Y1563763D03*
X1022623D03*
X994305Y1566342D03*
X1017023Y1563763D03*
X1011476Y1565175D03*
X1005658Y1565005D03*
X1000058D03*
X1039958Y1553705D03*
Y1548105D03*
Y1542505D03*
X1039358Y1571005D03*
Y1576605D03*
X1005658Y1575905D03*
X1033917Y1574834D03*
X1033717Y1569234D03*
X1000058Y1575905D03*
X1028423Y1574963D03*
X1028223Y1569363D03*
X994460Y1577240D03*
X1022823Y1574963D03*
X1022623Y1569363D03*
X1017223Y1574963D03*
X1017023Y1569363D03*
X994305Y1571942D03*
X1011676Y1576375D03*
X1011476Y1570775D03*
X1005658Y1570605D03*
X1000058D03*
X1078358Y1561105D03*
Y1566705D03*
X1072758Y1561105D03*
Y1566705D03*
X1067158Y1561105D03*
Y1566705D03*
X1061558Y1561105D03*
Y1566705D03*
X1055768Y1566675D03*
X1055418Y1560785D03*
X1055618Y1554885D03*
Y1549285D03*
Y1543685D03*
X1078358Y1572305D03*
X1072758D03*
X1067158D03*
X1061558D03*
X1055768Y1572275D03*
Y1577875D03*
G54D45*
X1490354Y124507D03*
G54D20*
X111024Y302303D03*
Y755059D03*
Y1207815D03*
X235236Y302303D03*
Y755059D03*
Y1207815D03*
X359449Y302303D03*
Y755059D03*
Y1207815D03*
X483661Y302303D03*
Y755059D03*
Y1207815D03*
X607874Y302303D03*
Y755059D03*
Y1207815D03*
X732087Y302303D03*
Y755059D03*
Y1207815D03*
X1098524Y-115157D03*
X1281693Y302303D03*
Y755059D03*
Y1207815D03*
X1405906Y302303D03*
Y755059D03*
Y1207815D03*
X1530118Y302303D03*
Y755059D03*
Y1207815D03*
X1654331Y302303D03*
Y755059D03*
Y1207815D03*
X1778543Y302303D03*
Y755059D03*
Y1207815D03*
X1902756Y302303D03*
Y755059D03*
Y1207815D03*
G54D22*
X119763Y550725D03*
Y546225D03*
Y555225D03*
X83100Y984800D03*
X78600D03*
X83100Y980300D03*
X78600D03*
Y989300D03*
X83100D03*
X124263Y546225D03*
Y550725D03*
Y555225D03*
X141978Y958572D03*
X142006Y978425D03*
X209863Y566625D03*
X637592Y593186D03*
X641792D03*
Y597386D03*
X637592D03*
X633392Y593186D03*
Y597386D03*
X629192Y593186D03*
Y597386D03*
X641792Y605786D03*
Y601586D03*
X637592D03*
Y605786D03*
X633392D03*
Y601586D03*
X629192D03*
Y605786D03*
X675913Y586555D03*
Y592955D03*
Y598155D03*
X672082Y582834D03*
X666882D03*
X661682D03*
X656482D03*
X695413Y600755D03*
X699613D03*
X669482Y613934D03*
Y609734D03*
X665282D03*
Y613934D03*
X661082D03*
Y609734D03*
X656882Y613934D03*
Y609734D03*
X675913Y603355D03*
X695413Y604955D03*
X691213Y613355D03*
X695413D03*
X699613D03*
X691213Y609155D03*
X695413D03*
X699613Y604955D03*
Y609155D03*
X703813Y592355D03*
Y596555D03*
Y600755D03*
X704399Y626799D03*
Y618399D03*
Y622599D03*
X703813Y613355D03*
Y609155D03*
Y604955D03*
X1040264Y-147256D03*
X1030264D03*
X1035264D03*
X1060264D03*
X1050264D03*
X1055264D03*
X1065264D03*
X1045264D03*
X1080264D03*
X1070264D03*
X1075264D03*
X1085264D03*
X1078098Y1652768D03*
X1073098D03*
X1083098D03*
X1088098D03*
X1110264Y-147256D03*
X1100264D03*
X1090264D03*
X1105264D03*
X1095264D03*
X1130264D03*
X1120264D03*
X1115264D03*
X1125264D03*
X1135264D03*
X1093098Y1652768D03*
X1170264Y-147256D03*
X1155264D03*
X1175602Y-137594D03*
Y-127594D03*
X1160264Y-147256D03*
X1150264D03*
X1140264D03*
X1145264D03*
X1175602Y-132594D03*
Y-142594D03*
X1165264Y-147256D03*
X1175602Y-117594D03*
Y-107594D03*
Y-97594D03*
Y-87594D03*
Y-77594D03*
Y-82594D03*
Y-92594D03*
Y-102594D03*
Y-112594D03*
Y-122594D03*
Y-67594D03*
Y-57594D03*
Y-47594D03*
Y-37594D03*
Y-32594D03*
Y-42594D03*
Y-52594D03*
Y-62594D03*
Y-72594D03*
Y-17594D03*
Y-27594D03*
X1180500Y4000D03*
X1176500Y-500D03*
X1175602Y-22594D03*
Y-12594D03*
Y-7594D03*
X1162000Y1371500D03*
X1169783Y1369303D03*
X1158673Y1417067D03*
Y1407067D03*
Y1397067D03*
Y1387067D03*
Y1377067D03*
Y1412067D03*
Y1402067D03*
Y1392067D03*
Y1382067D03*
Y1422067D03*
Y1442067D03*
Y1437067D03*
Y1427067D03*
Y1432067D03*
X1191382Y5500D03*
X1196382D03*
X1186382D03*
X1201382D03*
X1211382D03*
X1221382D03*
X1231382D03*
X1226382D03*
X1216382D03*
X1206382D03*
X1251382D03*
X1261382D03*
X1271382D03*
X1281382D03*
X1276382D03*
X1266382D03*
X1256382D03*
X1241382D03*
X1246382D03*
X1236382D03*
X1301382D03*
X1311382D03*
X1296382D03*
X1316382D03*
X1306382D03*
X1291382D03*
X1286382D03*
X1326382D03*
X1321382D03*
X1363579Y19821D03*
Y14821D03*
Y9821D03*
X1351382Y5500D03*
X1356382D03*
X1346382D03*
X1336382D03*
X1341382D03*
X1331382D03*
X1363579Y44821D03*
Y39821D03*
Y34821D03*
Y29821D03*
Y24821D03*
X1374000Y64500D03*
X1363579Y51618D03*
X1370200Y550500D03*
X1366000D03*
X1378100Y530200D03*
Y534400D03*
X1365500Y538600D03*
X1369700D03*
X1365500Y534400D03*
X1369700D03*
X1373900D03*
X1365500Y530200D03*
X1369700D03*
X1373900D03*
X1375900Y568500D03*
X1366000Y563100D03*
X1370200D03*
Y554700D03*
X1366000D03*
X1370200Y558900D03*
X1366000D03*
X1396500Y549500D03*
X1386500Y534400D03*
Y530200D03*
X1382300D03*
Y534400D03*
X1396500Y559900D03*
Y554700D03*
Y565100D03*
X1393000Y568500D03*
X1387300D03*
X1381600D03*
X1434441Y590424D03*
X1434581Y586136D03*
X1697261Y1004347D03*
X1692761D03*
Y999847D03*
Y995347D03*
X1697261D03*
Y999847D03*
X1783806Y989468D03*
X1850263Y964540D03*
X1850370Y960239D03*
X1845870D03*
X1845763Y964540D03*
Y956040D03*
X1850263D03*
G54D19*
X111024Y153681D03*
Y606437D03*
Y1059193D03*
X235236Y153681D03*
Y606437D03*
Y1059193D03*
X359449Y153681D03*
Y606437D03*
Y1059193D03*
X483661Y153681D03*
Y606437D03*
Y1059193D03*
X607874Y153681D03*
Y606437D03*
Y1059193D03*
X732087Y153681D03*
Y606437D03*
Y1059193D03*
X949902Y-115157D03*
X1281693Y153681D03*
Y606437D03*
Y1059193D03*
X1405906Y153681D03*
Y606437D03*
Y1059193D03*
X1530118Y153681D03*
Y606437D03*
Y1059193D03*
X1654331Y153681D03*
Y606437D03*
Y1059193D03*
X1778543Y153681D03*
Y606437D03*
Y1059193D03*
X1902756Y153681D03*
Y606437D03*
Y1059193D03*
G54D37*
X929331Y16536D03*
X937205Y20473D03*
Y12599D03*
Y67717D03*
X929331Y48032D03*
Y32284D03*
X937205Y44095D03*
Y36221D03*
Y28347D03*
X929331Y103150D03*
Y87402D03*
Y71654D03*
X937205Y114961D03*
Y99213D03*
Y83465D03*
X929331Y166142D03*
Y150394D03*
Y134646D03*
Y118898D03*
X937205Y162205D03*
Y146457D03*
Y130709D03*
X929331Y213386D03*
Y197638D03*
Y181890D03*
X937205Y209449D03*
Y193701D03*
Y177953D03*
X929331Y260630D03*
Y244882D03*
Y229134D03*
X937205Y256693D03*
Y240945D03*
Y225197D03*
X929331Y307874D03*
Y292126D03*
Y276378D03*
X937205Y303937D03*
Y288189D03*
Y272441D03*
X929331Y339371D03*
Y323622D03*
X937205Y335434D03*
Y319685D03*
X929331Y395669D03*
X937205Y407480D03*
Y399606D03*
Y391732D03*
X929331Y450787D03*
X937205Y446850D03*
X929331Y427165D03*
Y419291D03*
Y411417D03*
X937205Y431102D03*
Y423228D03*
Y415354D03*
X929331Y498031D03*
Y482283D03*
Y466535D03*
X937205Y494094D03*
Y478346D03*
Y462598D03*
X929331Y545275D03*
Y529527D03*
Y513779D03*
X937205Y541338D03*
Y525590D03*
Y509842D03*
X929331Y592519D03*
Y576771D03*
Y561023D03*
X937205Y588582D03*
Y572834D03*
Y557086D03*
X929331Y639763D03*
Y624015D03*
Y608267D03*
X937205Y635826D03*
Y620078D03*
Y604330D03*
X929331Y687007D03*
Y671259D03*
Y655511D03*
X937205Y683070D03*
Y667322D03*
Y651574D03*
X929331Y718504D03*
Y702755D03*
X937205Y714567D03*
Y698818D03*
X954921Y16536D03*
X947047Y20473D03*
Y12599D03*
X954921Y63780D03*
X947047Y67717D03*
X954921Y40158D03*
Y32284D03*
X947047Y51969D03*
Y44095D03*
Y36221D03*
Y28347D03*
X954921Y111024D03*
Y95276D03*
Y79528D03*
X947047Y107087D03*
Y91339D03*
Y75591D03*
X954921Y158268D03*
Y142520D03*
Y126772D03*
X947047Y154331D03*
Y138583D03*
Y122835D03*
X954921Y205512D03*
Y189764D03*
Y174016D03*
X947047Y201575D03*
Y185827D03*
Y170079D03*
X954921Y252756D03*
Y237008D03*
Y221260D03*
X947047Y248819D03*
Y233071D03*
Y217323D03*
X954921Y300000D03*
Y284252D03*
Y268504D03*
X947047Y296063D03*
Y280315D03*
Y264567D03*
X954921Y339371D03*
Y331496D03*
Y315748D03*
X947047Y327559D03*
Y311811D03*
X954921Y395669D03*
X947047Y407480D03*
Y399606D03*
Y391732D03*
X954921Y442913D03*
X947047Y454724D03*
X954921Y427165D03*
Y419291D03*
Y411417D03*
X947047Y431102D03*
Y423228D03*
X954921Y490157D03*
Y474409D03*
Y458661D03*
X947047Y501968D03*
Y486220D03*
Y470472D03*
X954921Y553149D03*
Y537401D03*
Y521653D03*
Y505905D03*
X947047Y549212D03*
Y533464D03*
Y517716D03*
X954921Y600393D03*
Y584645D03*
Y568897D03*
X947047Y596456D03*
Y580708D03*
Y564960D03*
X954921Y647637D03*
Y631889D03*
Y616141D03*
X947047Y643700D03*
Y627952D03*
Y612204D03*
X954921Y694881D03*
Y679133D03*
Y663385D03*
X947047Y690944D03*
Y675196D03*
Y659448D03*
X954921Y710629D03*
X947047Y706692D03*
X1123031Y16536D03*
X1097441D03*
X1115157Y20473D03*
Y12599D03*
X1105315Y20473D03*
Y12599D03*
X1123031Y63780D03*
X1115157Y67717D03*
X1105315D03*
X1123031Y40158D03*
Y32284D03*
X1097441Y48032D03*
Y32284D03*
X1115157Y51969D03*
Y44095D03*
Y36221D03*
Y28347D03*
X1105315Y44095D03*
Y36221D03*
Y28347D03*
X1123031Y111024D03*
Y95276D03*
Y79528D03*
X1097441Y103150D03*
Y87402D03*
Y71654D03*
X1115157Y107087D03*
Y91339D03*
Y75591D03*
X1105315Y114961D03*
Y99213D03*
Y83465D03*
X1123031Y158268D03*
Y142520D03*
Y126772D03*
X1097441Y166142D03*
Y150394D03*
Y134646D03*
Y118898D03*
X1115157Y154331D03*
Y138583D03*
Y122835D03*
X1105315Y162205D03*
Y146457D03*
Y130709D03*
X1123031Y205512D03*
Y189764D03*
Y174016D03*
X1097441Y213386D03*
Y197638D03*
Y181890D03*
X1115157Y201575D03*
Y185827D03*
Y170079D03*
X1105315Y209449D03*
Y193701D03*
Y177953D03*
X1123031Y252756D03*
Y237008D03*
Y221260D03*
X1097441Y260630D03*
Y244882D03*
Y229134D03*
X1115157Y248819D03*
Y233071D03*
Y217323D03*
X1105315Y256693D03*
Y240945D03*
Y225197D03*
X1123031Y300000D03*
Y284252D03*
Y268504D03*
X1097441Y307874D03*
Y292126D03*
Y276378D03*
X1115157Y296063D03*
Y280315D03*
Y264567D03*
X1105315Y303937D03*
Y288189D03*
Y272441D03*
X1123031Y339371D03*
Y331496D03*
Y315748D03*
X1097441Y339371D03*
Y323622D03*
X1115157Y327559D03*
Y311811D03*
X1105315Y335434D03*
Y319685D03*
X1123031Y395669D03*
X1097441D03*
X1115157Y407480D03*
Y399606D03*
Y391732D03*
X1105315Y407480D03*
Y399606D03*
Y391732D03*
X1123031Y442913D03*
X1097441Y450787D03*
X1115157Y454724D03*
X1105315Y446850D03*
X1123031Y427165D03*
Y419291D03*
Y411417D03*
X1097441Y427165D03*
Y419291D03*
Y411417D03*
X1115157Y431102D03*
Y423228D03*
X1105315Y431102D03*
Y423228D03*
Y415354D03*
X1123031Y490157D03*
Y474409D03*
Y458661D03*
X1097441Y498031D03*
Y482283D03*
Y466535D03*
X1115157Y501968D03*
Y486220D03*
Y470472D03*
X1105315Y494094D03*
Y478346D03*
Y462598D03*
X1123031Y553149D03*
Y537401D03*
Y521653D03*
Y505905D03*
X1097441Y545275D03*
Y529527D03*
Y513779D03*
X1115157Y549212D03*
Y533464D03*
Y517716D03*
X1105315Y541338D03*
Y525590D03*
Y509842D03*
X1123031Y600393D03*
Y584645D03*
Y568897D03*
X1097441Y592519D03*
Y576771D03*
Y561023D03*
X1115157Y596456D03*
Y580708D03*
Y564960D03*
X1105315Y588582D03*
Y572834D03*
Y557086D03*
X1123031Y647637D03*
Y631889D03*
Y616141D03*
X1097441Y639763D03*
Y624015D03*
Y608267D03*
X1115157Y643700D03*
Y627952D03*
Y612204D03*
X1105315Y635826D03*
Y620078D03*
Y604330D03*
X1123031Y694881D03*
Y679133D03*
Y663385D03*
X1097441Y687007D03*
Y671259D03*
Y655511D03*
X1115157Y690944D03*
Y675196D03*
Y659448D03*
X1105315Y683070D03*
Y667322D03*
Y651574D03*
X1123031Y710629D03*
X1097441Y718504D03*
Y702755D03*
X1115157Y706692D03*
X1105315Y714567D03*
Y698818D03*
G54D41*
X986614Y1619764D03*
X974016D03*
Y1597126D03*
X986614D03*
X974016Y1591220D03*
Y1603031D03*
Y1613858D03*
X986614Y1591220D03*
Y1613858D03*
Y1603031D03*
X974016Y1625669D03*
X986614D03*
X1030709Y1619764D03*
X1014961D03*
X1002362D03*
Y1597126D03*
X1014961D03*
X1030709D03*
X1002362Y1591220D03*
Y1603031D03*
Y1613858D03*
X1014961Y1591220D03*
Y1603031D03*
Y1613858D03*
X1030709Y1591220D03*
Y1613858D03*
Y1603031D03*
X1002362Y1642401D03*
X1014961D03*
X1030709D03*
X1002362Y1625669D03*
Y1636496D03*
Y1648307D03*
X1014961Y1625669D03*
Y1636496D03*
Y1648307D03*
X1030709Y1625669D03*
Y1636496D03*
Y1648307D03*
X1043307Y1619764D03*
Y1597126D03*
Y1591220D03*
Y1603031D03*
Y1613858D03*
Y1642401D03*
Y1625669D03*
Y1636496D03*
Y1648307D03*
X1101457Y1601181D03*
X1119685D03*
X1108150D03*
X1126378D03*
G54D29*
X313312Y98705D03*
X317812Y98905D03*
X450984Y124507D03*
X436811D03*
X479830D03*
X465157D03*
X550197D03*
X536023D03*
X521850D03*
X564370D03*
X753883Y929689D03*
Y937689D03*
Y945689D03*
X756250Y1140250D03*
X929331Y63780D03*
Y40158D03*
Y24410D03*
X937205Y51969D03*
X929331Y111024D03*
Y95276D03*
Y79528D03*
X937205Y107087D03*
Y91339D03*
Y75591D03*
X929331Y158268D03*
Y142520D03*
Y126772D03*
X937205Y154331D03*
Y138583D03*
Y122835D03*
X929331Y205512D03*
Y189764D03*
Y174016D03*
X937205Y201575D03*
Y185827D03*
Y170079D03*
X929331Y252756D03*
Y237008D03*
Y221260D03*
X937205Y248819D03*
Y233071D03*
Y217323D03*
X929331Y300000D03*
Y284252D03*
Y268504D03*
X937205Y296063D03*
Y280315D03*
Y264567D03*
X929331Y331496D03*
Y315748D03*
X937205Y327559D03*
Y311811D03*
X929331Y403543D03*
Y442913D03*
X937205Y454724D03*
X929331Y490157D03*
Y474409D03*
Y458661D03*
X937205Y501968D03*
Y486220D03*
Y470472D03*
X929331Y553149D03*
Y537401D03*
Y521653D03*
Y505905D03*
X937205Y549212D03*
Y533464D03*
Y517716D03*
X929331Y600393D03*
Y584645D03*
Y568897D03*
X937205Y596456D03*
Y580708D03*
Y564960D03*
X929331Y647637D03*
Y631889D03*
Y616141D03*
X937205Y643700D03*
Y627952D03*
Y612204D03*
X929331Y694881D03*
Y679133D03*
Y663385D03*
X937205Y690944D03*
Y675196D03*
Y659448D03*
X929331Y710629D03*
X937205Y706692D03*
X954921Y48032D03*
Y24410D03*
Y103150D03*
Y87402D03*
Y71654D03*
X947047Y114961D03*
Y99213D03*
Y83465D03*
X954921Y166142D03*
Y150394D03*
Y134646D03*
Y118898D03*
X947047Y162205D03*
Y146457D03*
Y130709D03*
X954921Y213386D03*
Y197638D03*
Y181890D03*
X947047Y209449D03*
Y193701D03*
Y177953D03*
X954921Y260630D03*
Y244882D03*
Y229134D03*
X947047Y256693D03*
Y240945D03*
Y225197D03*
X954921Y307874D03*
Y292126D03*
Y276378D03*
X947047Y303937D03*
Y288189D03*
Y272441D03*
X954921Y323622D03*
X947047Y335434D03*
Y319685D03*
X954921Y403543D03*
Y450787D03*
X947047Y446850D03*
Y415354D03*
X954921Y498031D03*
Y482283D03*
Y466535D03*
X947047Y494094D03*
Y478346D03*
Y462598D03*
X954921Y545275D03*
Y529527D03*
Y513779D03*
X947047Y541338D03*
Y525590D03*
Y509842D03*
X954921Y592519D03*
Y576771D03*
Y561023D03*
X947047Y588582D03*
Y572834D03*
Y557086D03*
X954921Y639763D03*
Y624015D03*
Y608267D03*
X947047Y635826D03*
Y620078D03*
Y604330D03*
X954921Y687007D03*
Y671259D03*
Y655511D03*
X947047Y683070D03*
Y667322D03*
Y651574D03*
X954921Y718504D03*
Y702755D03*
X947047Y714567D03*
Y698818D03*
X1097441Y63780D03*
X1123031Y48032D03*
Y24410D03*
X1097441Y40158D03*
Y24410D03*
X1105315Y51969D03*
X1123031Y103150D03*
Y87402D03*
Y71654D03*
X1097441Y111024D03*
Y95276D03*
Y79528D03*
X1115157Y114961D03*
Y99213D03*
Y83465D03*
X1105315Y107087D03*
Y91339D03*
Y75591D03*
X1123031Y166142D03*
Y150394D03*
Y134646D03*
Y118898D03*
X1097441Y158268D03*
Y142520D03*
Y126772D03*
X1115157Y162205D03*
Y146457D03*
Y130709D03*
X1105315Y154331D03*
Y138583D03*
Y122835D03*
X1123031Y213386D03*
Y197638D03*
Y181890D03*
X1097441Y205512D03*
Y189764D03*
Y174016D03*
X1115157Y209449D03*
Y193701D03*
Y177953D03*
X1105315Y201575D03*
Y185827D03*
Y170079D03*
X1123031Y260630D03*
Y244882D03*
Y229134D03*
X1097441Y252756D03*
Y237008D03*
Y221260D03*
X1115157Y256693D03*
Y240945D03*
Y225197D03*
X1105315Y248819D03*
Y233071D03*
Y217323D03*
X1123031Y307874D03*
Y292126D03*
Y276378D03*
X1097441Y300000D03*
Y284252D03*
Y268504D03*
X1115157Y303937D03*
Y288189D03*
Y272441D03*
X1105315Y296063D03*
Y280315D03*
Y264567D03*
X1123031Y323622D03*
X1097441Y331496D03*
Y315748D03*
X1115157Y335434D03*
Y319685D03*
X1105315Y327559D03*
Y311811D03*
X1123031Y403543D03*
X1097441D03*
X1123031Y450787D03*
X1097441Y442913D03*
X1115157Y446850D03*
X1105315Y454724D03*
X1115157Y415354D03*
X1123031Y498031D03*
Y482283D03*
Y466535D03*
X1097441Y490157D03*
Y474409D03*
Y458661D03*
X1115157Y494094D03*
Y478346D03*
Y462598D03*
X1105315Y501968D03*
Y486220D03*
Y470472D03*
X1123031Y545275D03*
Y529527D03*
Y513779D03*
X1097441Y553149D03*
Y537401D03*
Y521653D03*
Y505905D03*
X1115157Y541338D03*
Y525590D03*
Y509842D03*
X1105315Y549212D03*
Y533464D03*
Y517716D03*
X1123031Y592519D03*
Y576771D03*
Y561023D03*
X1097441Y600393D03*
Y584645D03*
Y568897D03*
X1115157Y588582D03*
Y572834D03*
Y557086D03*
X1105315Y596456D03*
Y580708D03*
Y564960D03*
X1123031Y639763D03*
Y624015D03*
Y608267D03*
X1097441Y647637D03*
Y631889D03*
Y616141D03*
X1115157Y635826D03*
Y620078D03*
Y604330D03*
X1105315Y643700D03*
Y627952D03*
Y612204D03*
X1123031Y687007D03*
Y671259D03*
Y655511D03*
X1097441Y694881D03*
Y679133D03*
Y663385D03*
X1115157Y683070D03*
Y667322D03*
Y651574D03*
X1105315Y690944D03*
Y675196D03*
Y659448D03*
X1123031Y718504D03*
Y702755D03*
X1097441Y710629D03*
X1115157Y714567D03*
Y698818D03*
X1105315Y706692D03*
X1334500Y202548D03*
Y207548D03*
Y212548D03*
Y217548D03*
X1334000Y666417D03*
Y661917D03*
Y657417D03*
Y652917D03*
X1334500Y1104700D03*
Y1111173D03*
Y1116173D03*
Y1121173D03*
X1413400Y575000D03*
X1384013Y631998D03*
Y619498D03*
X1447834Y124507D03*
X1458764Y212625D03*
Y208025D03*
Y203425D03*
Y217225D03*
X1458713Y658417D03*
Y663417D03*
Y668417D03*
Y652217D03*
X1461713Y1123173D03*
Y1118173D03*
Y1113173D03*
X1461700Y1107200D03*
X1504527Y124507D03*
X1518701D03*
X1508225Y631998D03*
Y619498D03*
X1532874Y124507D03*
X1565593Y654856D03*
X1565618Y660773D03*
Y665773D03*
Y670773D03*
X1582925Y210661D03*
Y205661D03*
Y200661D03*
Y215661D03*
X1632438Y631998D03*
Y619498D03*
X1707138Y210661D03*
Y205661D03*
Y200661D03*
Y215661D03*
X1707100Y652500D03*
X1707138Y658417D03*
Y663417D03*
Y668417D03*
Y1111173D03*
Y1116173D03*
Y1121173D03*
X1707200Y1105200D03*
X1831350Y210661D03*
Y205661D03*
Y200661D03*
Y215661D03*
Y658417D03*
Y663417D03*
Y668417D03*
X1831300Y652600D03*
X1828850Y1106173D03*
Y1111173D03*
Y1116173D03*
Y1121173D03*
X1880863Y179242D03*
Y166742D03*
G54D11*
X24508Y5500D03*
X20000Y60000D03*
X5500Y61492D03*
Y56492D03*
Y51492D03*
Y46492D03*
Y41492D03*
Y66492D03*
X20000Y80000D03*
Y100000D03*
X5500Y81492D03*
Y76492D03*
Y96492D03*
Y91492D03*
Y86492D03*
Y71492D03*
Y101492D03*
Y111492D03*
Y116492D03*
Y106492D03*
X20000Y120000D03*
Y140000D03*
Y160000D03*
X5500Y126492D03*
Y121492D03*
Y141492D03*
Y151492D03*
Y161492D03*
Y156492D03*
Y146492D03*
Y131492D03*
Y136492D03*
X20000Y180000D03*
Y200000D03*
X5500Y181492D03*
Y191492D03*
Y201492D03*
Y211492D03*
Y171492D03*
Y206492D03*
Y196492D03*
Y176492D03*
Y166492D03*
Y186492D03*
X20000Y220000D03*
Y240000D03*
Y260000D03*
X5500Y231492D03*
Y241492D03*
Y251492D03*
Y261492D03*
Y221492D03*
Y256492D03*
Y246492D03*
Y226492D03*
Y216492D03*
Y236492D03*
X20000Y280000D03*
Y300000D03*
X5500Y281492D03*
Y291492D03*
Y301492D03*
Y271492D03*
Y306492D03*
Y296492D03*
Y286492D03*
Y276492D03*
Y266492D03*
X20000Y320000D03*
Y340000D03*
X5500Y331492D03*
Y341492D03*
Y351492D03*
Y311492D03*
Y321492D03*
Y356492D03*
Y346492D03*
Y336492D03*
Y326492D03*
Y316492D03*
X20000Y360000D03*
Y380000D03*
Y400000D03*
X5500Y381492D03*
Y391492D03*
Y401492D03*
Y361492D03*
Y371492D03*
Y406492D03*
Y396492D03*
Y386492D03*
Y376492D03*
Y366492D03*
X20000Y420000D03*
Y440000D03*
X5500Y451492D03*
Y441492D03*
Y431492D03*
Y421492D03*
Y411492D03*
Y416492D03*
Y436492D03*
Y446492D03*
Y426492D03*
Y501492D03*
Y456492D03*
Y496492D03*
Y531492D03*
Y551492D03*
Y541492D03*
Y521492D03*
Y511492D03*
Y536492D03*
Y546492D03*
Y506492D03*
Y516492D03*
Y526492D03*
Y581492D03*
Y591492D03*
Y571492D03*
Y561492D03*
Y586492D03*
Y596492D03*
Y556492D03*
Y566492D03*
Y576492D03*
Y631492D03*
Y641492D03*
Y621492D03*
Y611492D03*
Y601492D03*
Y636492D03*
Y646492D03*
Y606492D03*
Y616492D03*
Y626492D03*
Y681492D03*
Y691492D03*
Y671492D03*
Y661492D03*
Y651492D03*
Y686492D03*
Y696492D03*
Y656492D03*
Y666492D03*
Y676492D03*
Y731492D03*
Y741492D03*
Y721492D03*
Y711492D03*
Y701492D03*
Y736492D03*
Y706492D03*
Y716492D03*
Y726492D03*
Y781492D03*
Y791492D03*
Y771492D03*
Y761492D03*
Y751492D03*
Y786492D03*
Y746492D03*
Y756492D03*
Y766492D03*
Y776492D03*
Y831492D03*
Y841492D03*
Y821492D03*
Y811492D03*
Y801492D03*
Y836492D03*
Y796492D03*
Y806492D03*
Y816492D03*
Y826492D03*
Y881492D03*
Y871492D03*
Y861492D03*
Y851492D03*
Y886492D03*
Y846492D03*
Y856492D03*
Y866492D03*
Y876492D03*
X15000Y930000D03*
Y920000D03*
X25000Y930000D03*
Y920000D03*
X5500Y931492D03*
Y921492D03*
Y911492D03*
Y901492D03*
Y891492D03*
Y936492D03*
Y896492D03*
Y906492D03*
Y916492D03*
Y926492D03*
X15000Y980000D03*
Y970000D03*
Y960000D03*
Y950000D03*
Y940000D03*
X25000D03*
Y950000D03*
Y960000D03*
Y970000D03*
Y980000D03*
X5500Y976492D03*
Y981492D03*
Y986492D03*
Y966492D03*
Y956492D03*
Y961492D03*
Y971492D03*
Y951492D03*
Y941492D03*
Y946492D03*
X15000Y1030000D03*
Y1020000D03*
Y1010000D03*
Y1000000D03*
Y990000D03*
X25000D03*
Y1000000D03*
Y1010000D03*
Y1020000D03*
X5500Y991492D03*
Y996492D03*
Y1001492D03*
Y1006492D03*
Y1026492D03*
Y1016492D03*
Y1011492D03*
Y1021492D03*
Y1031492D03*
X25000Y1040000D03*
Y1080000D03*
Y1070000D03*
Y1060000D03*
Y1050000D03*
X5500Y1036492D03*
Y1066492D03*
Y1056492D03*
Y1046492D03*
Y1041492D03*
Y1051492D03*
Y1061492D03*
Y1071492D03*
Y1081492D03*
Y1076492D03*
X25000Y1090000D03*
X5500Y1121492D03*
Y1131492D03*
Y1111492D03*
Y1101492D03*
Y1091492D03*
Y1086492D03*
Y1096492D03*
Y1106492D03*
Y1116492D03*
Y1126492D03*
Y1171492D03*
Y1161492D03*
Y1151492D03*
Y1141492D03*
Y1136492D03*
Y1146492D03*
Y1156492D03*
Y1166492D03*
Y1176492D03*
Y1221492D03*
Y1211492D03*
Y1201492D03*
Y1191492D03*
Y1181492D03*
Y1186492D03*
Y1196492D03*
Y1206492D03*
Y1216492D03*
Y1226492D03*
X17500Y1270000D03*
Y1260000D03*
Y1250000D03*
Y1240000D03*
X5500Y1271492D03*
Y1261492D03*
Y1251492D03*
Y1241492D03*
Y1231492D03*
Y1236492D03*
Y1246492D03*
Y1256492D03*
Y1266492D03*
Y1276492D03*
X17500Y1290000D03*
Y1280000D03*
Y1300000D03*
Y1310000D03*
X5500Y1321492D03*
Y1311492D03*
Y1301492D03*
Y1291492D03*
Y1281492D03*
Y1286492D03*
Y1296492D03*
Y1306492D03*
Y1316492D03*
X17500Y1320000D03*
Y1360000D03*
Y1350000D03*
Y1330000D03*
Y1340000D03*
X8983Y1368303D03*
X13983D03*
X18983D03*
X23983D03*
X5500Y1361492D03*
Y1351492D03*
Y1341492D03*
Y1331492D03*
Y1336492D03*
Y1346492D03*
Y1356492D03*
Y1326492D03*
X60000Y20000D03*
X29508Y5500D03*
X39508D03*
X34508D03*
X44508D03*
X64508D03*
X69508D03*
X54508D03*
X49508D03*
X59508D03*
X60000Y40000D03*
X40000D03*
X60000Y60000D03*
X40000D03*
Y80000D03*
X60000D03*
Y100000D03*
X40000D03*
X60000Y120000D03*
X40000D03*
Y140000D03*
X60000D03*
Y160000D03*
X40000D03*
X38500Y202000D03*
X64487Y212761D03*
X56000Y237000D03*
X49437Y254661D03*
X62000Y276500D03*
X40000Y280000D03*
Y300000D03*
X60000D03*
Y320000D03*
X40000D03*
X60000Y340000D03*
X40000D03*
Y360000D03*
X35000Y446500D03*
X50500Y545500D03*
X58346Y516473D03*
X54088Y512336D03*
X39853Y512373D03*
X44111Y516510D03*
X40000Y560000D03*
Y580000D03*
Y600000D03*
Y620000D03*
X39000Y646000D03*
X30697Y679553D03*
X31043Y689115D03*
X30676Y663764D03*
X49500Y729000D03*
X49437Y707417D03*
X31064Y704904D03*
X51000Y755500D03*
X38500Y800500D03*
X39000Y834500D03*
X49000Y811000D03*
X51000Y846000D03*
X40000Y930000D03*
Y920000D03*
Y970000D03*
Y960000D03*
Y950000D03*
Y940000D03*
X67500Y961355D03*
X72500D03*
X50000Y1030000D03*
X40000Y1000000D03*
Y990000D03*
X50000Y1060000D03*
X30256Y1116731D03*
X30670Y1132472D03*
X30644Y1157871D03*
X30623Y1142082D03*
X45800Y1306100D03*
X37500Y1360000D03*
X27500D03*
X28983Y1368303D03*
X33983D03*
X38983D03*
X43983D03*
X48983D03*
X53983D03*
X58983D03*
X63983D03*
X68983D03*
X114508Y5500D03*
X119508D03*
X104508D03*
X94508D03*
X84508D03*
X74508D03*
X79508D03*
X89508D03*
X99508D03*
X109508D03*
X80000Y80000D03*
X100000D03*
X120000D03*
Y100000D03*
X100000D03*
X80000D03*
X120000Y120000D03*
X100000D03*
X80000D03*
X86500Y157500D03*
X80000Y140000D03*
X118437Y141870D03*
X78500Y169500D03*
X111437Y165492D03*
Y180492D03*
X74937Y187461D03*
X73937Y201661D03*
X78937D03*
X83937D03*
X88937D03*
X100000Y480000D03*
X120000Y500000D03*
X100000D03*
X104500Y515500D03*
X120500Y524000D03*
X86500Y522000D03*
X100000Y541500D03*
X87000Y541000D03*
X89000Y557500D03*
X108500Y572000D03*
X88000Y577500D03*
X118753Y594626D03*
X88000Y602500D03*
X111437Y633248D03*
Y618248D03*
X74937Y640217D03*
X88937Y654417D03*
X83937D03*
X78937D03*
X73937D03*
Y1107173D03*
X78937D03*
X83937D03*
X88937D03*
X98500Y1241000D03*
X90000Y1252500D03*
X86000Y1282000D03*
X93000Y1319000D03*
X73983Y1368303D03*
X78983D03*
X83983D03*
X88983D03*
X93983D03*
X98983D03*
X107374Y1369303D03*
X112374D03*
X117374D03*
X160000Y20000D03*
X134508Y5500D03*
X124508D03*
X129508D03*
X169508D03*
X159508D03*
X149508D03*
X139508D03*
X154508D03*
X164508D03*
X144508D03*
X160000Y60000D03*
Y40000D03*
X140000D03*
Y60000D03*
X160000Y100000D03*
Y80000D03*
X140000D03*
Y100000D03*
X160000Y140000D03*
X140000D03*
X160000Y120000D03*
X140000D03*
X156500Y170500D03*
X160000Y180000D03*
X142500Y515500D03*
X150000Y526500D03*
X135000Y588000D03*
X167000Y613000D03*
X147500Y605500D03*
X122374Y1369303D03*
X127374D03*
X132374D03*
X137374D03*
X142374D03*
X147374D03*
X152374D03*
X157374D03*
X162374D03*
X167374D03*
X200000Y20000D03*
X180000D03*
X209508Y5500D03*
X199508D03*
X189508D03*
X179508D03*
X204508D03*
X214508D03*
X174508D03*
X184508D03*
X194508D03*
X200000Y40000D03*
X180000D03*
X200000Y60000D03*
X180000D03*
Y80000D03*
X200000D03*
Y100000D03*
X180000D03*
Y120000D03*
X200000D03*
Y140000D03*
X180000D03*
X199149Y187461D03*
X198149Y201661D03*
X203149D03*
X208149D03*
X213149D03*
X216499Y636917D03*
X199149Y631217D03*
X210849Y638617D03*
X198149Y654417D03*
X203149D03*
X208149D03*
X213149D03*
X216712Y961155D03*
X198149Y1107173D03*
X203149D03*
X208149D03*
X213149D03*
X181000Y1261000D03*
X190000Y1320000D03*
X200000D03*
X210000D03*
Y1300000D03*
Y1310000D03*
X200000D03*
X190000D03*
X172374Y1369303D03*
X177374D03*
X182374D03*
X187374D03*
X192374D03*
X197374D03*
X202374D03*
X207374D03*
X212374D03*
X217374D03*
X260000Y20000D03*
X220000D03*
X240000D03*
X259508Y5500D03*
X249508D03*
X239508D03*
X229508D03*
X219508D03*
X224508D03*
X234508D03*
X244508D03*
X254508D03*
X264508D03*
X260000Y60000D03*
Y40000D03*
X240000D03*
X220000D03*
Y60000D03*
X240000D03*
X260000Y100000D03*
Y80000D03*
X240000D03*
X220000D03*
Y100000D03*
X240000D03*
X260000Y140000D03*
Y120000D03*
X240000D03*
X220000D03*
X242649Y141870D03*
X235649Y165492D03*
Y180492D03*
X243051Y594626D03*
X235649Y633248D03*
Y618248D03*
X221712Y961155D03*
X257000Y1253000D03*
X220000Y1270000D03*
Y1320000D03*
X230000D03*
X240000D03*
X250000D03*
X260000D03*
X220000Y1280000D03*
X230000D03*
X250000Y1290000D03*
X240000D03*
X230000D03*
X220000D03*
Y1300000D03*
X230000D03*
X240000D03*
X250000D03*
X260000D03*
Y1310000D03*
X250000D03*
X240000D03*
X230000D03*
X220000D03*
X222374Y1369303D03*
X227374D03*
X232374D03*
X237374D03*
X242374D03*
X247374D03*
X252374D03*
X257374D03*
X262374D03*
X300000Y20000D03*
X280000D03*
X309508Y5500D03*
X299508D03*
X289508D03*
X279508D03*
X269508D03*
X304508D03*
X314508D03*
X274508D03*
X284508D03*
X294508D03*
X300000Y40000D03*
X280000Y60000D03*
Y40000D03*
Y100000D03*
Y80000D03*
X312355Y72855D03*
X280000Y140000D03*
Y120000D03*
X270000Y179500D03*
X285500Y189500D03*
X283000Y181000D03*
X282263Y589225D03*
X270263D03*
X274263D03*
X286263D03*
X290263D03*
X278263D03*
X277000Y618500D03*
X275000Y647000D03*
X294500Y607500D03*
X284000D03*
X301000Y1231000D03*
X267374Y1369303D03*
X272374D03*
X277374D03*
X282374D03*
X287374D03*
X292374D03*
X297374D03*
X302374D03*
X307374D03*
X312374D03*
X360000Y20000D03*
X340000D03*
X320000D03*
X359508Y5500D03*
X349508D03*
X339508D03*
X329508D03*
X319508D03*
X324508D03*
X334508D03*
X344508D03*
X354508D03*
X360000Y40000D03*
X340000D03*
X320000D03*
X355200Y58400D03*
X346245Y58745D03*
X353001Y81799D03*
X351000Y70700D03*
X328000Y150500D03*
X333021Y129679D03*
X359862Y165492D03*
Y180492D03*
X323362Y187461D03*
X322362Y201661D03*
X327362D03*
X332362D03*
X337362D03*
X333000Y580000D03*
Y604000D03*
X359862Y648248D03*
Y633248D03*
Y618248D03*
X323362Y640217D03*
X355362Y670197D03*
X359862Y688248D03*
X355362Y660748D03*
Y651299D03*
X322362Y654417D03*
X327362D03*
X332362D03*
X337362D03*
X359862Y728248D03*
Y718248D03*
Y698248D03*
X355000Y780500D03*
X361500Y901500D03*
X360000Y940000D03*
X320925Y961355D03*
X315925D03*
X322362Y1107173D03*
X327362D03*
X332362D03*
X337362D03*
X353000Y1231000D03*
X330000Y1302000D03*
X333983Y1368303D03*
X338983D03*
X343983D03*
X348983D03*
X353983D03*
X358983D03*
X363983D03*
X317374Y1369303D03*
X322374D03*
X327374D03*
X380000Y20000D03*
X395075Y18639D03*
Y13639D03*
X389508Y5500D03*
X379508D03*
X369508D03*
X364508D03*
X374508D03*
X384508D03*
X394508D03*
X380000Y60000D03*
Y40000D03*
X395075Y43639D03*
Y38639D03*
Y33639D03*
Y28639D03*
Y23639D03*
X399000Y62000D03*
X396000Y55500D03*
X396075Y50248D03*
X401000Y89000D03*
X400000Y80000D03*
X365162Y88731D03*
Y77731D03*
X388500Y153500D03*
X395500Y160500D03*
X366862Y141870D03*
X389000Y594500D03*
X366862Y594626D03*
X395000Y631000D03*
X388000Y607000D03*
X410000Y692500D03*
X379000Y664000D03*
X391112Y689917D03*
X402129Y744503D03*
X388796Y732042D03*
X402138Y720413D03*
X402181Y710325D03*
X402500Y780500D03*
X366862Y766870D03*
X397000Y911000D03*
X380000Y940000D03*
X383849Y1190833D03*
X388849Y1191148D03*
X368983Y1368303D03*
X373983D03*
X378983D03*
X383983D03*
X388983D03*
X393983D03*
X398983D03*
X403983D03*
X408983D03*
X447574Y187461D03*
X440138Y508600D03*
X445138D03*
X417000Y652500D03*
X454500Y672000D03*
X446074Y687417D03*
X437224Y665417D03*
X456574Y654417D03*
X451574D03*
X446574D03*
X452500Y744500D03*
X437500Y744000D03*
X422074Y707417D03*
X446074Y699917D03*
X455000Y780000D03*
X445000D03*
X440000Y760000D03*
X445000Y798000D03*
X440138Y961355D03*
X445138D03*
X454500Y1248500D03*
X460000Y1320000D03*
X440000D03*
X460000Y1300000D03*
X413983Y1368303D03*
X418983D03*
X423983D03*
X428983D03*
X433983D03*
X438983D03*
X443983D03*
X448983D03*
X453983D03*
X458983D03*
X476319Y144481D03*
X506750Y165324D03*
X497785Y178034D03*
X479574Y670197D03*
X484074Y688248D03*
X461574Y654417D03*
X484074Y728248D03*
Y718248D03*
Y698248D03*
X461874Y729617D03*
X461500Y769500D03*
X491074Y766870D03*
X468074Y752917D03*
X500000Y940000D03*
X480000D03*
Y1320000D03*
X500000Y1300000D03*
X480000D03*
Y1280000D03*
X463983Y1368303D03*
X468983D03*
X473983D03*
X478983D03*
X483983D03*
X488983D03*
X493983D03*
X498983D03*
X503983D03*
X508983D03*
X534350Y508600D03*
X539350D03*
X515324Y689917D03*
X526225Y744756D03*
X546287Y707417D03*
X512892Y732295D03*
X526277Y710578D03*
X526234Y720666D03*
X509000Y772000D03*
X555500Y852000D03*
X551500Y888000D03*
X523500Y883500D03*
X525000Y937000D03*
X514474Y1107073D03*
X519474D03*
X524474D03*
X529474D03*
X539000Y1309000D03*
X517374Y1369303D03*
X522374D03*
X527374D03*
X532374D03*
X537374D03*
X542374D03*
X547374D03*
X552374D03*
X557374D03*
X597051Y7699D03*
Y12699D03*
Y17699D03*
X604146Y5500D03*
X597051Y22699D03*
Y27699D03*
Y32699D03*
Y37699D03*
Y42699D03*
X589000Y64000D03*
X594000Y61500D03*
X596000Y56500D03*
X596051Y51090D03*
X603697Y182091D03*
X568687Y187660D03*
X582697Y200744D03*
X577697D03*
X572697D03*
X587697D03*
X579000Y672000D03*
X603787Y670197D03*
X570287Y687417D03*
X561437Y665417D03*
X585787Y654417D03*
X580787D03*
X575787D03*
X570787D03*
X559000Y741000D03*
X586087Y729617D03*
X570287Y699917D03*
X603000Y781000D03*
X592287Y752917D03*
X604000Y897000D03*
X592000Y900500D03*
X569350Y961355D03*
X564350D03*
X570787Y1107173D03*
X575787D03*
X580787D03*
X585787D03*
X590000Y1247000D03*
X567374Y1369303D03*
X572374D03*
X577374D03*
X582374D03*
X587374D03*
X592374D03*
X597374D03*
X602374D03*
X562374D03*
X609146Y5500D03*
X619146D03*
X614146D03*
X629146D03*
X639146D03*
X649146D03*
X654146D03*
X644146D03*
X634146D03*
X624146D03*
X613500Y66000D03*
X634500Y77000D03*
X629024Y107633D03*
X614967Y134777D03*
X606718Y168580D03*
X652663Y516600D03*
X647663D03*
X608287Y688248D03*
X639537Y689917D03*
X650659Y744673D03*
X608287Y728248D03*
Y718248D03*
Y698248D03*
X637326Y732212D03*
X650668Y720583D03*
X650711Y710495D03*
X631500Y774000D03*
X615287Y766870D03*
X642000Y889500D03*
X632000Y936000D03*
X654000Y911000D03*
X646500Y898500D03*
X617374Y1369303D03*
X622374D03*
X627374D03*
X632374D03*
X637374D03*
X642374D03*
X647374D03*
X652374D03*
X607374D03*
X612374D03*
X679146Y5500D03*
X689146D03*
X694146D03*
X684146D03*
X659146D03*
X669146D03*
X664146D03*
X674146D03*
X699146D03*
X700000Y60000D03*
X675000Y75500D03*
X697457Y107247D03*
X697483Y111500D03*
X661965Y106177D03*
X658500Y184500D03*
X699950Y200846D03*
X694950D03*
X694500Y687417D03*
X685550Y665417D03*
X700000Y654417D03*
X695000D03*
X670500Y707417D03*
X694500Y699917D03*
X691500Y778000D03*
X692500Y790500D03*
X678500Y776500D03*
X673500Y752000D03*
X695000Y1107173D03*
X700000D03*
X698500Y1306500D03*
X667374Y1369303D03*
X672374D03*
X677374D03*
X682374D03*
X687374D03*
X692374D03*
X697374D03*
X702374D03*
X657374D03*
X662374D03*
X749146Y5500D03*
X709146D03*
X719146D03*
X729146D03*
X739146D03*
X744146D03*
X734146D03*
X724146D03*
X714146D03*
X704146D03*
X740000Y40000D03*
X720000D03*
Y60000D03*
X740000D03*
X732500Y180492D03*
X728000Y207992D03*
Y198543D03*
X732100Y198373D03*
X709950Y200846D03*
X704950D03*
X728000Y217441D03*
X732500Y245492D03*
X731048Y238563D03*
X738361Y306612D03*
X732500Y275492D03*
Y265492D03*
X724000Y338500D03*
X748000Y368500D03*
X726000Y369000D03*
X732000Y374500D03*
Y383000D03*
X748500Y409000D03*
X721500Y462500D03*
X727500Y476000D03*
X724000Y583500D03*
X739500Y594626D03*
X732500Y648248D03*
Y633248D03*
Y618248D03*
X704500Y672000D03*
X728000Y670197D03*
X732500Y688248D03*
X728000Y660748D03*
Y651299D03*
X710000Y654417D03*
X705000D03*
X732500Y728248D03*
Y718248D03*
Y698248D03*
X710300Y729617D03*
X748000Y783000D03*
X739500Y766870D03*
X716500Y752917D03*
X745000Y833000D03*
X704500Y795000D03*
X747656Y876717D03*
X709500Y894500D03*
X732500Y1071004D03*
X739500Y1047382D03*
X728000Y1122953D03*
Y1113504D03*
Y1104055D03*
X732500Y1101004D03*
Y1086004D03*
X705000Y1107173D03*
X710000D03*
X732500Y1141004D03*
X747374Y1369303D03*
X742374D03*
X717374D03*
X722374D03*
X727374D03*
X732374D03*
X737374D03*
X707374D03*
X712374D03*
X795969Y-1374D03*
X759146Y5500D03*
X769146D03*
X774146D03*
X764146D03*
X754146D03*
X779146D03*
X789045Y11615D03*
X760000Y40000D03*
X752950Y213450D03*
X771500Y311000D03*
X764000Y439500D03*
X767500Y463500D03*
X772000Y479500D03*
X787000Y514000D03*
X798140Y630220D03*
X798210Y626440D03*
X798367Y622400D03*
X751750Y685300D03*
X793000Y828000D03*
Y851000D03*
X778000Y988500D03*
X762500D03*
X763000Y1075000D03*
X781000Y1373000D03*
X755500Y1374500D03*
X752500Y1370500D03*
X757287Y1380873D03*
Y1385873D03*
Y1390873D03*
Y1395873D03*
Y1400873D03*
Y1405873D03*
Y1410873D03*
Y1415873D03*
Y1420873D03*
X784000Y1443000D03*
X757287Y1425873D03*
Y1430873D03*
Y1435873D03*
Y1440873D03*
Y1445873D03*
X766156Y1462004D03*
X771156D03*
X790500Y1466500D03*
X786000Y1463500D03*
X756287Y1459264D03*
Y1454264D03*
X779547Y1463004D03*
X792902Y1477964D03*
Y1487964D03*
Y1497964D03*
Y1507964D03*
Y1517964D03*
Y1512964D03*
Y1472964D03*
Y1482964D03*
Y1492964D03*
Y1502964D03*
Y1562964D03*
Y1527964D03*
Y1537964D03*
Y1547964D03*
Y1557964D03*
Y1567964D03*
Y1522964D03*
Y1532964D03*
Y1542964D03*
Y1552964D03*
Y1612964D03*
Y1602964D03*
Y1592964D03*
Y1582964D03*
Y1572964D03*
Y1577964D03*
Y1587964D03*
Y1597964D03*
Y1607964D03*
X797902Y1652964D03*
X792902D03*
Y1642964D03*
Y1632964D03*
Y1622964D03*
Y1627964D03*
Y1637964D03*
Y1647964D03*
Y1617964D03*
X845961Y61762D03*
X818300Y39845D03*
X814300D03*
Y43845D03*
X818300D03*
X846000Y116500D03*
X811500Y372000D03*
X800000Y400000D03*
X811500Y469500D03*
X846400Y469300D03*
X839000Y541000D03*
X839500Y560000D03*
X800867Y619400D03*
X803367Y622400D03*
X827500Y922500D03*
X839414Y1520763D03*
X833859Y1594095D03*
Y1608268D03*
X840945Y1598032D03*
X826772D03*
X840945Y1612205D03*
X826772D03*
X833859Y1622441D03*
Y1636614D03*
Y1650788D03*
X840945Y1626378D03*
X826772D03*
X840945Y1640551D03*
X826772D03*
X872642Y-140575D03*
Y-135575D03*
Y-130575D03*
Y-125575D03*
X890264Y-147256D03*
X880264D03*
X875264D03*
X885264D03*
X895264D03*
X882000Y-105500D03*
X872642Y-80575D03*
Y-120575D03*
Y-115575D03*
Y-110575D03*
Y-105575D03*
Y-100575D03*
Y-95575D03*
Y-90575D03*
Y-85575D03*
Y-30575D03*
Y-35575D03*
Y-40575D03*
Y-45575D03*
Y-50575D03*
Y-55575D03*
Y-60575D03*
Y-65575D03*
Y-70575D03*
Y-75575D03*
Y-20575D03*
Y-25575D03*
X885046Y20384D03*
X861101Y66680D03*
X862099Y61626D03*
Y56626D03*
X861961Y52762D03*
X852769Y66957D03*
X848769D03*
X856769D03*
X853961Y52762D03*
X857961D03*
X874244Y37026D03*
Y44935D03*
X858496Y37121D03*
X854180Y36996D03*
X852995Y40965D03*
X856995D03*
X852769Y74957D03*
X856769D03*
X861142Y71026D03*
X852810Y71303D03*
X856810D03*
X853900Y89701D03*
X888500Y260500D03*
X850500Y266000D03*
X866000Y315000D03*
X856500Y373000D03*
X855500Y499500D03*
X871487Y463589D03*
X860092Y542405D03*
X867500Y643000D03*
X877000Y664500D03*
X868500Y665000D03*
X885600Y824400D03*
X867663Y818831D03*
X873800Y1418200D03*
X871432Y1420932D03*
X874900Y1421900D03*
X877406Y1419124D03*
X875740Y1415070D03*
X872192Y1424492D03*
X882000Y1432600D03*
X870921Y1432300D03*
X889002Y1489638D03*
X873972Y1472467D03*
X873922Y1477766D03*
X855092Y1535821D03*
X866621Y1544206D03*
X876378Y1594095D03*
X862205D03*
X848032D03*
X876378Y1608268D03*
X862205D03*
X848032D03*
X890552Y1598032D03*
X869292D03*
X855118D03*
X869292Y1612205D03*
X855118D03*
X876378Y1622441D03*
X862205D03*
X848032D03*
X876378Y1636614D03*
X862205D03*
X848032D03*
X876378Y1650788D03*
X862205D03*
X848032D03*
X869292Y1626378D03*
X855118D03*
X869292Y1640551D03*
X855118D03*
X910500Y-137500D03*
X940264Y-147256D03*
X930264D03*
X925264D03*
X935264D03*
X920264D03*
X910264D03*
X900264D03*
X905264D03*
X915264D03*
X902000Y-58000D03*
X909000Y89000D03*
X898000Y133000D03*
X911000Y305500D03*
X898000Y268000D03*
X911811Y1594095D03*
Y1598425D03*
X897638Y1594095D03*
X960264Y-147256D03*
X950264D03*
X955264D03*
X965264D03*
X945264D03*
X990264D03*
X980264D03*
X970264D03*
X975264D03*
X985264D03*
X975500Y11500D03*
X974000Y402000D03*
Y523000D03*
X985500Y613500D03*
X978000Y677000D03*
X1010264Y-147256D03*
X1000264D03*
X1005264D03*
X1015264D03*
X995264D03*
X1020264D03*
X1025264D03*
X1036713Y-115500D03*
X993000Y108000D03*
Y157000D03*
Y329000D03*
X995000Y455000D03*
Y488000D03*
X993000Y635000D03*
X1085300Y-90700D03*
X1066600Y-72800D03*
X1066225Y-40278D03*
X1054593Y-51122D03*
X1085800Y-57100D03*
X1054800Y22405D03*
X1042800Y442000D03*
X1072000Y1035000D03*
X1137446Y1024025D03*
Y1009852D03*
Y995679D03*
Y1038198D03*
Y1167343D03*
Y1224036D03*
Y1209863D03*
Y1195690D03*
Y1181516D03*
Y1266556D03*
Y1252383D03*
Y1238209D03*
Y1309076D03*
Y1323249D03*
Y1294902D03*
Y1280729D03*
Y1365769D03*
Y1351595D03*
Y1337422D03*
Y1394115D03*
Y1408288D03*
Y1379942D03*
X1133098Y1652768D03*
X1123098D03*
X1113098D03*
X1103098D03*
X1108098D03*
X1118098D03*
X1128098D03*
X1098098D03*
X1185000Y281343D03*
X1176100Y270603D03*
X1176300Y288600D03*
X1179783Y1369303D03*
X1174783D03*
X1184783D03*
X1147900Y1421500D03*
X1158673Y1452067D03*
X1158500Y1468500D03*
X1158673Y1457067D03*
Y1447067D03*
Y1462067D03*
X1143900Y1431000D03*
X1142400Y1427700D03*
X1146002Y1427906D03*
X1145007Y1424446D03*
X1148556Y1425056D03*
X1153000Y1496000D03*
X1161000Y1474500D03*
X1166673Y1477941D03*
X1171673D03*
X1181673D03*
X1176673D03*
X1163000Y1612000D03*
X1141000Y1632000D03*
X1143098Y1652768D03*
X1183098D03*
X1173098D03*
X1163098D03*
X1153098D03*
X1158098D03*
X1168098D03*
X1178098D03*
X1138098D03*
X1148098D03*
X1186600Y253200D03*
X1215547Y246355D03*
X1194600Y288237D03*
X1198130Y1151410D03*
X1214500Y1320500D03*
X1220500Y1311000D03*
X1199783Y1369303D03*
X1209783D03*
X1219783D03*
X1229783D03*
X1189783D03*
X1224783D03*
X1214783D03*
X1204783D03*
X1194783D03*
X1194000Y1499000D03*
X1191673Y1477941D03*
X1201673D03*
X1214972Y1482642D03*
Y1517642D03*
Y1487642D03*
Y1497642D03*
Y1507642D03*
Y1512642D03*
Y1502642D03*
Y1492642D03*
X1206673Y1477941D03*
X1196673D03*
X1186673D03*
X1211673D03*
X1214972Y1567642D03*
Y1527642D03*
Y1537642D03*
Y1547642D03*
Y1557642D03*
Y1562642D03*
Y1552642D03*
Y1542642D03*
Y1532642D03*
Y1522642D03*
Y1577642D03*
Y1587642D03*
Y1597642D03*
Y1607642D03*
Y1612642D03*
Y1602642D03*
Y1592642D03*
Y1582642D03*
Y1572642D03*
Y1617642D03*
Y1627642D03*
Y1637642D03*
X1213098Y1652768D03*
X1193098D03*
X1203098D03*
X1208098D03*
X1214972Y1642642D03*
Y1632642D03*
X1188098Y1652768D03*
X1198098D03*
X1214972Y1622642D03*
Y1647642D03*
X1257000Y1300000D03*
X1263500Y1318500D03*
X1249783Y1369303D03*
X1259783D03*
X1269783D03*
X1279783D03*
X1239783D03*
X1274783D03*
X1264783D03*
X1254783D03*
X1234783D03*
X1244783D03*
X1320055Y68000D03*
X1327921Y78900D03*
X1308228Y93399D03*
X1324134Y126967D03*
X1313127Y120839D03*
X1315118Y126967D03*
X1300065Y1206008D03*
X1305000Y1205173D03*
X1313000D03*
X1289106Y1219626D03*
X1299783Y1369303D03*
X1309783D03*
X1319783D03*
X1329783D03*
X1289783D03*
X1324783D03*
X1314783D03*
X1304783D03*
X1294783D03*
X1284783D03*
X1372000Y335000D03*
X1346057Y529857D03*
X1373700Y582900D03*
X1369500D03*
X1377900Y587100D03*
Y591300D03*
Y595500D03*
X1373700D03*
Y591300D03*
Y587100D03*
X1369500Y595500D03*
Y591300D03*
Y587100D03*
X1377900Y599700D03*
X1373700D03*
X1369500D03*
X1367382Y961355D03*
X1362382D03*
X1351321Y1152553D03*
X1349783Y1369303D03*
X1359783D03*
X1369783D03*
X1339783D03*
X1374783D03*
X1364783D03*
X1354783D03*
X1344783D03*
X1334783D03*
X1426400Y307400D03*
X1400000Y406000D03*
X1427000Y380000D03*
X1425000Y480000D03*
X1405000D03*
Y460000D03*
X1385000Y480000D03*
X1396500Y511000D03*
X1383500Y509500D03*
X1413319Y594626D03*
X1382100Y587100D03*
X1386300D03*
X1406319Y648248D03*
Y633248D03*
Y618248D03*
X1401819Y651299D03*
X1413319Y1219626D03*
X1422713Y1205173D03*
X1413000Y1241500D03*
X1387000Y1243500D03*
X1386500Y1258000D03*
X1418000Y1291500D03*
X1400000Y1320000D03*
X1420000D03*
X1399783Y1369303D03*
X1409783D03*
X1419783D03*
X1379783D03*
X1389783D03*
X1404783D03*
X1414783D03*
X1424783D03*
X1394783D03*
X1384783D03*
X1463000Y307000D03*
X1439300Y301500D03*
X1429800Y302500D03*
X1447170Y337890D03*
X1466500Y338100D03*
X1441770Y365790D03*
X1461100Y366000D03*
X1441970Y403990D03*
X1461300Y404200D03*
X1439500Y421500D03*
X1440000Y460000D03*
X1449576Y495482D03*
X1468605Y493549D03*
X1452279Y563600D03*
X1464700Y585600D03*
X1470000Y580000D03*
X1460274Y592498D03*
X1428013Y636417D03*
X1435413Y625417D03*
X1431713Y615417D03*
X1439713Y647917D03*
X1470953Y1152427D03*
X1475953D03*
X1429213Y1205173D03*
X1437213D03*
X1458000Y1265500D03*
X1460000Y1300000D03*
Y1320000D03*
X1440000D03*
X1449783Y1369303D03*
X1459783D03*
X1469783D03*
X1429783D03*
X1439783D03*
X1444783D03*
X1454783D03*
X1464783D03*
X1474783D03*
X1434783D03*
X1515450Y181700D03*
X1502950D03*
X1505000Y378500D03*
X1520000Y421500D03*
X1479212Y535612D03*
X1494100Y526400D03*
X1507900Y539100D03*
X1481938Y512568D03*
X1509911Y553511D03*
X1478700Y579100D03*
X1502400Y554100D03*
X1491594Y961355D03*
X1486594D03*
X1480000Y1320000D03*
X1499783Y1369303D03*
X1509783D03*
X1519783D03*
X1479783D03*
X1489783D03*
X1494783D03*
X1484783D03*
X1504783D03*
X1514783D03*
X1565555Y16517D03*
X1568030Y5500D03*
X1565555Y21517D03*
Y26517D03*
Y31517D03*
Y36517D03*
Y41517D03*
X1557000Y64500D03*
X1561500Y62000D03*
X1564000Y57500D03*
X1564555Y52124D03*
X1525336Y149369D03*
X1555925Y162661D03*
X1545383Y164116D03*
X1560000Y140000D03*
X1552225Y183661D03*
X1559625Y172661D03*
X1530531Y195492D03*
Y180492D03*
X1546925Y299661D03*
X1553425D03*
X1561425D03*
X1537531Y314114D03*
X1545000Y455000D03*
X1560000D03*
X1525000D03*
X1545000Y475000D03*
X1560000D03*
Y500000D03*
Y525000D03*
X1552000Y584500D03*
X1566000Y595000D03*
X1537531Y594626D03*
X1552225Y636417D03*
X1559625Y625417D03*
X1555925Y615417D03*
X1530531Y633248D03*
Y618248D03*
X1547800Y1098819D03*
X1552800D03*
X1557800D03*
X1562800D03*
X1546898Y1204827D03*
X1553425Y1208897D03*
X1561425Y1205173D03*
X1537879Y1219626D03*
X1549783Y1369303D03*
X1559783D03*
X1569783D03*
X1529783D03*
X1539783D03*
X1524783D03*
X1534783D03*
X1544783D03*
X1554783D03*
X1564783D03*
X1600000Y20000D03*
X1620000D03*
X1580000D03*
X1603030Y5500D03*
X1613030D03*
X1573030D03*
X1583030D03*
X1593030D03*
X1618030D03*
X1608030D03*
X1598030D03*
X1588030D03*
X1578030D03*
X1600000Y60000D03*
X1620000Y40000D03*
X1600000D03*
X1580000D03*
Y60000D03*
X1620000Y100000D03*
X1600000Y80000D03*
X1620000D03*
X1580000D03*
X1620000Y140000D03*
Y120000D03*
X1585757Y134147D03*
X1600000Y340000D03*
Y320000D03*
X1579500Y331000D03*
X1597245Y516662D03*
X1583030Y517405D03*
X1615807Y508600D03*
X1610807D03*
X1573000Y565500D03*
X1615807Y961355D03*
X1610807D03*
X1615909Y1150262D03*
X1581500Y1240000D03*
X1600000Y1320000D03*
X1614783Y1369303D03*
X1604783D03*
X1599783D03*
X1609783D03*
X1619783D03*
X1579783D03*
X1589783D03*
X1574783D03*
X1584783D03*
X1594783D03*
X1640000Y20000D03*
X1660000D03*
X1653030Y5500D03*
X1663030D03*
X1623030D03*
X1633030D03*
X1643030D03*
X1668030D03*
X1658030D03*
X1648030D03*
X1638030D03*
X1628030D03*
X1640000Y60000D03*
X1660000D03*
Y40000D03*
X1640000D03*
Y100000D03*
X1660000D03*
X1640000Y80000D03*
X1660000D03*
Y120000D03*
X1640000D03*
X1661744Y141870D03*
X1660000Y520000D03*
X1640000D03*
X1660000Y540000D03*
X1640000D03*
Y560000D03*
X1660000D03*
X1661744Y594626D03*
X1654744Y648248D03*
Y633248D03*
Y618248D03*
X1623888Y689917D03*
X1652962Y670204D03*
X1654744Y688248D03*
X1650244Y660748D03*
Y651299D03*
X1637000Y729000D03*
X1638000Y740000D03*
X1654744Y728248D03*
Y718248D03*
Y698248D03*
X1630000Y780000D03*
Y760000D03*
X1661744Y766870D03*
X1625000Y800000D03*
X1651500Y913500D03*
X1650000Y950000D03*
X1661744Y1219626D03*
X1640000Y1260000D03*
X1660000D03*
X1640000Y1320000D03*
Y1300000D03*
X1660000Y1320000D03*
Y1300000D03*
Y1280000D03*
X1640000D03*
X1664783Y1369303D03*
X1654783D03*
X1644783D03*
X1634783D03*
X1624783D03*
X1649783D03*
X1659783D03*
X1629783D03*
X1639783D03*
X1700000Y20000D03*
X1680000D03*
X1703030Y5500D03*
X1713030D03*
X1673030D03*
X1683030D03*
X1693030D03*
X1718030D03*
X1708030D03*
X1698030D03*
X1688030D03*
X1678030D03*
X1700000Y60000D03*
Y40000D03*
X1680000Y60000D03*
Y40000D03*
Y100000D03*
Y80000D03*
X1700000Y100000D03*
Y80000D03*
Y140000D03*
Y120000D03*
X1680000D03*
X1679500Y144000D03*
X1680000Y520000D03*
X1700000Y540000D03*
X1680000D03*
X1700000Y560000D03*
X1680000D03*
X1676438Y636417D03*
X1683838Y625417D03*
X1680138Y615417D03*
X1688138Y648017D03*
X1675138Y718917D03*
X1686638Y717417D03*
X1710000Y770000D03*
Y785000D03*
X1685000Y770000D03*
X1671138Y752417D03*
X1677638D03*
X1685638D03*
X1709000Y915000D03*
X1687000Y905500D03*
X1716500Y943500D03*
X1685638Y1205173D03*
X1677638D03*
X1671138D03*
X1680000Y1240000D03*
X1700000Y1260000D03*
X1680000D03*
X1700000Y1320000D03*
Y1300000D03*
Y1280000D03*
X1680000Y1320000D03*
Y1300000D03*
Y1280000D03*
X1714783Y1369303D03*
X1704783D03*
X1694783D03*
X1684783D03*
X1674783D03*
X1699783D03*
X1709783D03*
X1669783D03*
X1679783D03*
X1689783D03*
X1760000Y20000D03*
X1740000D03*
X1720000D03*
X1753030Y5500D03*
X1763030D03*
X1723030D03*
X1733030D03*
X1743030D03*
X1758030D03*
X1748030D03*
X1738030D03*
X1728030D03*
X1760000Y60000D03*
Y40000D03*
X1740000D03*
Y60000D03*
X1720000Y40000D03*
Y60000D03*
X1740000Y100000D03*
X1760000D03*
X1740000Y80000D03*
X1760000D03*
X1720000Y100000D03*
Y80000D03*
X1740000Y140000D03*
X1760000Y120000D03*
X1740000D03*
X1720000Y140000D03*
Y120000D03*
X1740019Y508600D03*
X1735019D03*
X1735000Y785000D03*
X1730000Y775000D03*
X1725000Y800000D03*
X1718000Y876000D03*
X1740019Y961355D03*
X1735019D03*
X1718117Y1152553D03*
X1723117D03*
X1728000Y1204500D03*
X1720000Y1320000D03*
X1760000D03*
X1753000Y1302000D03*
X1764783Y1369303D03*
X1754783D03*
X1744783D03*
X1734783D03*
X1724783D03*
X1749783D03*
X1759783D03*
X1719783D03*
X1729783D03*
X1739783D03*
X1778030Y5500D03*
X1793030D03*
X1803030D03*
X1813030D03*
X1808030D03*
X1798030D03*
X1783030D03*
X1788030D03*
X1773030D03*
X1768030D03*
X1780000Y60000D03*
Y40000D03*
X1800000Y100000D03*
Y80000D03*
X1780000Y100000D03*
Y80000D03*
X1800000Y120000D03*
X1780000D03*
X1785956Y141870D03*
X1773500Y879500D03*
X1771000Y944500D03*
X1799000Y945500D03*
X1782666Y961344D03*
X1777666D03*
X1795350Y1205173D03*
X1801850D03*
X1809850D03*
X1785956Y1219626D03*
X1772111Y1232695D03*
X1804783Y1369303D03*
X1794783D03*
X1784783D03*
X1774783D03*
X1799783D03*
X1809783D03*
X1769783D03*
X1779783D03*
X1789783D03*
X1843030Y5500D03*
X1853030D03*
X1863030D03*
X1838030D03*
X1858030D03*
X1848030D03*
X1823030D03*
X1833030D03*
X1828030D03*
X1818030D03*
X1860000Y60000D03*
Y80000D03*
Y100000D03*
X1840000D03*
X1820000D03*
X1860000Y140000D03*
Y120000D03*
X1840000D03*
X1820000Y140000D03*
Y120000D03*
X1859232Y508600D03*
X1836400Y1151900D03*
X1860000Y1320000D03*
X1854783Y1369303D03*
X1844783D03*
X1834783D03*
X1824783D03*
X1814783D03*
X1849783D03*
X1859783D03*
X1819783D03*
X1829783D03*
X1839783D03*
X1878030Y5500D03*
X1883030D03*
X1873030D03*
X1868030D03*
X1909030D03*
X1888030D03*
X1880000Y60000D03*
X1900000D03*
X1880000Y80000D03*
X1900000D03*
Y100000D03*
X1880000D03*
X1900000Y120000D03*
X1880000Y140000D03*
Y120000D03*
X1910169Y141870D03*
X1898669Y207992D03*
Y198543D03*
X1903169Y195492D03*
Y180492D03*
Y165492D03*
X1885204Y184345D03*
X1865669Y201661D03*
X1870669D03*
X1875669D03*
X1880669D03*
X1903169Y245492D03*
X1898669Y217441D03*
X1903169Y235492D03*
Y275492D03*
Y265492D03*
X1910169Y314114D03*
X1890000Y400000D03*
Y380000D03*
Y360000D03*
Y420000D03*
X1864232Y508600D03*
X1879669Y652917D03*
X1874669D03*
X1869669D03*
X1864669D03*
X1892443Y894350D03*
X1884200Y895000D03*
X1903169Y1071004D03*
X1910169Y1047382D03*
X1898669Y1122953D03*
Y1113504D03*
Y1104055D03*
X1903169Y1101004D03*
Y1086004D03*
X1864833Y1091419D03*
X1870779Y1091763D03*
X1875779D03*
X1880779D03*
X1863131Y1133108D03*
X1903169Y1171004D03*
X1903100Y1149700D03*
X1903169Y1141004D03*
X1864352Y1153308D03*
X1871174Y1138730D03*
X1887169Y1205673D03*
X1910169Y1219626D03*
X1903169Y1181004D03*
X1880969Y1182373D03*
X1900000Y1260000D03*
Y1280000D03*
Y1320000D03*
Y1300000D03*
X1904783Y1369303D03*
X1894783D03*
X1884783D03*
X1874783D03*
X1864783D03*
X1899783D03*
X1909783D03*
X1869783D03*
X1879783D03*
X1889783D03*
X1929343Y16525D03*
Y11525D03*
Y6525D03*
X1914030Y5500D03*
X1919030D03*
X1924030D03*
X1920000Y60000D03*
X1929343Y46525D03*
Y41525D03*
Y36525D03*
Y31525D03*
Y26525D03*
Y21525D03*
Y66525D03*
Y61525D03*
Y56525D03*
Y51525D03*
X1920000Y80000D03*
Y100000D03*
X1929343Y116525D03*
Y111525D03*
Y106525D03*
Y101525D03*
Y96525D03*
Y91525D03*
Y86525D03*
Y81525D03*
Y76525D03*
Y71525D03*
X1920000Y120000D03*
X1929343Y121525D03*
Y126525D03*
Y136525D03*
Y146525D03*
Y156525D03*
Y161525D03*
Y151525D03*
Y141525D03*
Y131525D03*
Y176525D03*
Y186525D03*
Y196525D03*
Y206525D03*
Y166525D03*
Y211525D03*
Y201525D03*
Y191525D03*
Y181525D03*
Y171525D03*
Y226525D03*
Y236525D03*
Y246525D03*
Y256525D03*
Y216525D03*
Y261525D03*
Y251525D03*
Y241525D03*
Y231525D03*
Y221525D03*
Y276525D03*
Y286525D03*
Y296525D03*
Y306525D03*
Y266525D03*
Y301525D03*
Y291525D03*
Y281525D03*
Y271525D03*
Y326525D03*
Y336525D03*
Y346525D03*
Y356525D03*
Y316525D03*
Y351525D03*
Y341525D03*
Y331525D03*
Y321525D03*
Y311525D03*
Y376525D03*
Y386525D03*
Y396525D03*
Y406525D03*
Y366525D03*
Y401525D03*
Y391525D03*
Y381525D03*
Y371525D03*
Y361525D03*
Y426525D03*
Y436525D03*
Y446525D03*
Y416525D03*
Y451525D03*
Y441525D03*
Y431525D03*
Y421525D03*
Y411525D03*
Y476525D03*
Y486525D03*
Y496525D03*
Y456525D03*
Y466525D03*
Y501525D03*
Y491525D03*
Y481525D03*
Y471525D03*
Y461525D03*
Y526525D03*
Y536525D03*
Y546525D03*
Y506525D03*
Y516525D03*
Y551525D03*
Y541525D03*
Y531525D03*
Y521525D03*
Y511525D03*
Y576525D03*
Y586525D03*
Y596525D03*
Y556525D03*
Y566525D03*
Y591525D03*
Y581525D03*
Y571525D03*
Y561525D03*
Y626525D03*
Y636525D03*
Y646525D03*
Y606525D03*
Y616525D03*
Y641525D03*
Y631525D03*
Y621525D03*
Y611525D03*
Y601525D03*
Y676525D03*
Y686525D03*
Y696525D03*
Y656525D03*
Y666525D03*
Y691525D03*
Y681525D03*
Y671525D03*
Y661525D03*
Y651525D03*
Y726525D03*
Y736525D03*
Y706525D03*
Y716525D03*
Y741525D03*
Y731525D03*
Y721525D03*
Y711525D03*
Y701525D03*
Y776525D03*
Y786525D03*
Y746525D03*
Y756525D03*
Y766525D03*
Y791525D03*
Y781525D03*
Y771525D03*
Y761525D03*
Y751525D03*
Y826525D03*
Y836525D03*
Y796525D03*
Y806525D03*
Y816525D03*
Y841525D03*
Y831525D03*
Y821525D03*
Y811525D03*
Y801525D03*
Y876525D03*
Y886525D03*
Y846525D03*
Y856525D03*
Y866525D03*
Y881525D03*
Y871525D03*
Y861525D03*
Y851525D03*
Y926525D03*
Y896525D03*
Y906525D03*
Y916525D03*
Y931525D03*
Y921525D03*
Y911525D03*
Y901525D03*
Y891525D03*
Y936525D03*
Y973863D03*
Y978863D03*
Y983863D03*
Y951525D03*
Y956525D03*
Y961525D03*
Y966525D03*
Y946525D03*
Y941525D03*
Y988863D03*
Y993863D03*
Y998863D03*
Y1003863D03*
Y1008863D03*
Y1033863D03*
Y1028863D03*
Y1023863D03*
Y1018863D03*
Y1013863D03*
Y1073863D03*
Y1083863D03*
Y1043863D03*
Y1053863D03*
Y1063863D03*
Y1078863D03*
Y1068863D03*
Y1058863D03*
Y1048863D03*
Y1038863D03*
Y1123863D03*
Y1093863D03*
Y1103863D03*
Y1113863D03*
Y1128863D03*
Y1118863D03*
Y1108863D03*
Y1098863D03*
Y1088863D03*
Y1173863D03*
Y1133863D03*
Y1143863D03*
Y1153863D03*
Y1163863D03*
Y1178863D03*
Y1168863D03*
Y1158863D03*
Y1148863D03*
Y1138863D03*
Y1223863D03*
Y1183863D03*
Y1193863D03*
Y1203863D03*
Y1213863D03*
Y1228863D03*
Y1218863D03*
Y1208863D03*
Y1198863D03*
Y1188863D03*
X1920000Y1260000D03*
X1929343Y1273863D03*
Y1233863D03*
Y1243863D03*
Y1253863D03*
Y1263863D03*
Y1268863D03*
Y1258863D03*
Y1248863D03*
Y1238863D03*
X1920000Y1280000D03*
Y1320000D03*
Y1300000D03*
X1929343Y1323863D03*
Y1283863D03*
Y1293863D03*
Y1303863D03*
Y1313863D03*
Y1318863D03*
Y1308863D03*
Y1298863D03*
Y1288863D03*
Y1278863D03*
Y1333863D03*
Y1343863D03*
Y1353863D03*
X1924783Y1369303D03*
X1914783D03*
X1919783D03*
X1929343Y1358863D03*
Y1348863D03*
Y1338863D03*
Y1328863D03*
Y1363863D03*
G54D35*
X702483Y945989D03*
X730882Y888502D03*
X716233Y868219D03*
X733422Y857828D03*
X721552Y951317D03*
X725852Y951067D03*
X763883Y907689D03*
X755883D03*
X750883Y903689D03*
X868100Y685600D03*
X871700D03*
X875300D03*
X884600Y688800D03*
X881000D03*
X877400D03*
X891000Y743500D03*
X870500Y762500D03*
X1843731Y936066D03*
X1843811Y940067D03*
X1830665Y941751D03*
X1836165D03*
G54D24*
X153263Y568725D03*
X146263D03*
X144263Y573225D03*
X138763Y568725D03*
X148763Y576225D03*
X188614Y591491D03*
X182500Y559200D03*
Y571200D03*
Y575200D03*
X178500D03*
Y571200D03*
X182500Y567200D03*
X186500Y559200D03*
Y563200D03*
Y567200D03*
X182500Y563200D03*
X186500Y575200D03*
Y571200D03*
X199102Y969717D03*
Y974717D03*
X183584Y974789D03*
Y969789D03*
X199392Y985113D03*
X183551Y984789D03*
X212063Y976725D03*
X203063D03*
X207563D03*
X216563D03*
X212063Y981725D03*
X216563D03*
X207563D03*
X203063D03*
X199392Y990113D03*
X183551Y989789D03*
X250650Y556997D03*
Y561997D03*
X265545Y556794D03*
Y561794D03*
X250661Y572936D03*
Y577936D03*
X265590Y572801D03*
Y577801D03*
X225563Y976725D03*
X221063D03*
X225563Y981725D03*
X221063D03*
X269763Y569725D03*
X287763D03*
X292263D03*
X274263D03*
X283263D03*
X278763D03*
X283263Y564725D03*
X287763D03*
X292263D03*
X274263D03*
X269763D03*
X278763D03*
X858632Y399200D03*
X855032D03*
Y395600D03*
X858632D03*
X855032Y392000D03*
X858632D03*
X852832Y406400D03*
Y402800D03*
X856432Y406400D03*
Y402800D03*
X852832Y410000D03*
X856432D03*
X1398493Y314114D03*
X1840419Y945557D03*
Y951057D03*
X1825945Y945449D03*
Y950949D03*
X1825741Y969210D03*
Y974210D03*
X1840683Y969318D03*
Y974318D03*
X1825744Y986011D03*
X1840578Y985885D03*
X1844863Y983125D03*
X1853863D03*
X1858363D03*
X1849363D03*
X1862863D03*
X1853863Y978125D03*
X1844863D03*
X1849363D03*
X1862863D03*
X1858363D03*
X1825744Y991011D03*
X1840578Y990885D03*
X1867363Y983125D03*
Y978125D03*
G54D36*
X944882Y-63877D03*
G54D38*
X942126Y58465D03*
Y346457D03*
Y437598D03*
Y725590D03*
X1110236Y58465D03*
Y346457D03*
Y437598D03*
Y725590D03*
G54D32*
X496653Y80906D03*
X1465157D03*
G54D16*
X60540Y-85109D03*
X59536Y1573374D03*
X79000Y1301900D03*
X1826700Y77600D03*
X1865705Y1573374D03*
X1898432Y-93682D03*
X1908500Y1346800D03*
G54D12*
X15157Y474409D03*
X904921Y-25591D03*
X1894684Y474409D03*
G54D18*
X80019Y51968D03*
X127263Y20472D03*
X631200Y51968D03*
X678444Y20472D03*
X1250689Y51969D03*
X1297933Y20472D03*
X1801870Y51969D03*
X1849114Y20472D03*
G54D10*
X15157Y21653D03*
X904921Y564960D03*
X1894685Y21654D03*
G54D33*
X496653Y110552D03*
X1465157D03*
G54D25*
X173228Y1062992D03*
X421653Y1141732D03*
X670079Y1062992D03*
X1343701D03*
X1592126Y1141732D03*
X1840551Y1062992D03*
G54D34*
X503248Y829921D03*
X1673917D03*
G54D13*
X31496Y882677D03*
X168307Y646457D03*
X660236D03*
X718110Y820866D03*
X1366142Y646457D03*
X1462992Y866929D03*
X1602756Y646457D03*
X1903346Y803937D03*
G54D39*
X975787Y-25590D03*
G54D17*
X103642Y36220D03*
X654822D03*
X1274311D03*
X1825492D03*
G54D26*
X173228Y1114173D03*
X670079D03*
X1343700D03*
X1840551D03*
G54D40*
X975786Y564960D03*
G54D44*
X1104527Y1630792D03*
G54D15*
X25000Y1190400D03*
X47000Y1107500D03*
X30000Y1190400D03*
X135422Y1190937D03*
X140422D03*
X264594Y1190768D03*
X259594D03*
X446951Y213656D03*
X451951D03*
X456951D03*
X461951D03*
X508103Y1190557D03*
X513103D03*
X632316Y1190474D03*
X637316D03*
X748500Y1287500D03*
X870163Y836153D03*
X865663Y834403D03*
X974016Y1642401D03*
X986614D03*
X974016Y1636496D03*
Y1648307D03*
X986614Y1636496D03*
Y1648307D03*
X1066750Y1224035D03*
X1079250D03*
X1066750Y1209862D03*
X1079250D03*
X1066750Y1216949D03*
X1079250D03*
X1066750Y1231122D03*
X1079250D03*
X1066750Y1238209D03*
X1079250D03*
X1066750Y1245295D03*
X1079250D03*
X1066750Y1301988D03*
X1079250D03*
X1066750Y1309075D03*
X1079250D03*
X1066750Y1316161D03*
X1079250D03*
X1066750Y1323248D03*
X1079250D03*
X1066750Y1294902D03*
X1079250D03*
X1066750Y1330335D03*
X1079250D03*
X1066750Y1387028D03*
X1079250D03*
X1066750Y1394114D03*
X1079250D03*
X1066750Y1401201D03*
X1079250D03*
X1066750Y1408287D03*
X1079250D03*
X1066750Y1415374D03*
X1079250D03*
X1066750Y1379941D03*
X1079250D03*
G54D30*
X322545Y72845D03*
X376413Y634498D03*
Y646998D03*
X500625Y634498D03*
Y646998D03*
X624838Y634498D03*
Y646998D03*
X749051Y194242D03*
Y181742D03*
Y634498D03*
Y646998D03*
X708683Y876958D03*
X749051Y1087254D03*
Y1099754D03*
X928600Y-115200D03*
X986713Y-115570D03*
X971713D03*
X1091089Y988592D03*
X1105262D03*
X1119435D03*
X1133609D03*
X1095026Y995678D03*
X1109199D03*
X1123372D03*
X1091089Y1002765D03*
X1105262D03*
X1119435D03*
X1133609D03*
X1095026Y1009852D03*
X1109199D03*
X1123372D03*
X1091089Y1016938D03*
X1105262D03*
X1119435D03*
X1133609D03*
X1095026Y1024025D03*
X1109199D03*
X1123372D03*
X1091089Y1031111D03*
X1105262D03*
X1119435D03*
X1133609D03*
X1095026Y1038198D03*
X1109199D03*
X1123372D03*
X1091089Y1160257D03*
Y1174430D03*
X1105262Y1160257D03*
Y1174430D03*
X1119435Y1160257D03*
Y1174430D03*
X1133609Y1160257D03*
Y1174430D03*
X1095026Y1167343D03*
X1109199D03*
X1123372D03*
X1091089Y1188603D03*
Y1202776D03*
Y1216949D03*
X1105262Y1188603D03*
Y1202776D03*
Y1216949D03*
X1119435Y1188603D03*
Y1202776D03*
Y1216949D03*
X1133609Y1188603D03*
Y1202776D03*
Y1216949D03*
X1095026Y1181516D03*
Y1195690D03*
Y1209863D03*
Y1224036D03*
X1109199Y1181516D03*
Y1195690D03*
Y1209863D03*
Y1224036D03*
X1123372Y1181516D03*
Y1195690D03*
Y1209863D03*
Y1224036D03*
X1091089Y1231123D03*
Y1245296D03*
Y1259469D03*
Y1273642D03*
X1105262Y1231123D03*
Y1245296D03*
Y1259469D03*
Y1273642D03*
X1119435Y1231123D03*
Y1245296D03*
Y1259469D03*
Y1273642D03*
X1133609Y1231123D03*
Y1245296D03*
Y1259469D03*
Y1273642D03*
X1095026Y1238209D03*
Y1252382D03*
Y1266556D03*
X1109199Y1238209D03*
Y1252382D03*
Y1266556D03*
X1123372Y1238209D03*
Y1252382D03*
Y1266556D03*
X1091089Y1287816D03*
Y1301989D03*
Y1316162D03*
X1105262Y1287816D03*
Y1301989D03*
Y1316162D03*
X1119435Y1287816D03*
Y1301989D03*
Y1316162D03*
X1133609Y1287816D03*
Y1301989D03*
Y1316162D03*
X1095026Y1280729D03*
Y1294902D03*
Y1309075D03*
Y1323249D03*
X1109199Y1280729D03*
Y1294902D03*
Y1309075D03*
Y1323249D03*
X1123372Y1280729D03*
Y1294902D03*
Y1309075D03*
Y1323249D03*
X1091089Y1330335D03*
Y1344508D03*
Y1358682D03*
Y1372855D03*
X1105262Y1330335D03*
Y1344508D03*
Y1358682D03*
Y1372855D03*
X1119435Y1330335D03*
Y1344508D03*
Y1358682D03*
Y1372855D03*
X1133609Y1330335D03*
Y1344508D03*
Y1358682D03*
Y1372855D03*
X1095026Y1337422D03*
Y1351595D03*
Y1365768D03*
X1109199Y1337422D03*
Y1351595D03*
Y1365768D03*
X1123372Y1337422D03*
Y1351595D03*
Y1365768D03*
X1091089Y1387028D03*
Y1401201D03*
X1105262Y1387028D03*
Y1401201D03*
X1119435Y1387028D03*
Y1401201D03*
X1133609Y1387028D03*
Y1401201D03*
X1095026Y1379942D03*
Y1394115D03*
Y1408288D03*
X1109199Y1379942D03*
Y1394115D03*
Y1408288D03*
X1123372Y1379942D03*
Y1394115D03*
Y1408288D03*
X1101457Y1588583D03*
X1119685D03*
X1108150D03*
X1126378D03*
X1402713Y634498D03*
Y646998D03*
X1526925Y181742D03*
Y194242D03*
Y634498D03*
X1651138D03*
Y646998D03*
X1899563Y181742D03*
Y194242D03*
Y1087254D03*
Y1099754D03*
G54D27*
X265275Y596896D03*
X250974Y597308D03*
X265275Y602396D03*
X250974Y602808D03*
X436811Y67914D03*
X450984D03*
X429724Y92323D03*
Y106496D03*
Y78150D03*
X436811Y82087D03*
X450984D03*
X443898Y92323D03*
X458071D03*
X436811Y96260D03*
X450984D03*
X443898Y106496D03*
X458071D03*
X436811Y110433D03*
X450984D03*
X443898Y78150D03*
X458071D03*
X429724Y120670D03*
X443898D03*
X458071D03*
X465157Y67914D03*
X479331D03*
X465157Y82087D03*
Y96260D03*
Y110433D03*
X479331Y82087D03*
X472244Y92323D03*
X479331Y96260D03*
X472244Y106496D03*
X479331Y110433D03*
X472244Y78150D03*
Y120670D03*
X550197Y67914D03*
X536024D03*
X521850D03*
X514764Y106496D03*
Y92323D03*
Y78150D03*
X550197Y110433D03*
X536024D03*
X521850D03*
X543110Y106496D03*
X528937D03*
X550197Y96260D03*
X536024D03*
X521850D03*
X543110Y92323D03*
X528937D03*
X550197Y82087D03*
X536024D03*
X521850D03*
X543110Y78150D03*
X528937D03*
X557283Y106496D03*
Y92323D03*
Y78150D03*
X514764Y120670D03*
X543110D03*
X528937D03*
X557283D03*
X564370Y67914D03*
Y110433D03*
Y96260D03*
Y82087D03*
X1405315Y67914D03*
X1419488D03*
X1398228Y92323D03*
Y106496D03*
Y78150D03*
X1405315Y82087D03*
X1419488D03*
X1412402Y92323D03*
X1426575D03*
X1405315Y96260D03*
X1419488D03*
X1412402Y106496D03*
X1426575D03*
X1405315Y110433D03*
X1419488D03*
X1412402Y78150D03*
X1426575D03*
X1398228Y120670D03*
X1412402D03*
X1426575D03*
X1433661Y67914D03*
X1447835D03*
X1433661Y82087D03*
Y96260D03*
Y110433D03*
X1447835Y82087D03*
X1440748Y92323D03*
X1447835Y96260D03*
X1440748Y106496D03*
X1447835Y110433D03*
X1440748Y78150D03*
Y120670D03*
X1518701Y67914D03*
X1504528D03*
X1490354D03*
X1483268Y116339D03*
Y110827D03*
Y102166D03*
Y96654D03*
Y78150D03*
X1518701Y110433D03*
X1504528D03*
X1511614Y106496D03*
X1518701Y96260D03*
X1504528D03*
X1511614Y92323D03*
X1497441D03*
X1518701Y82087D03*
X1504528D03*
X1490354D03*
X1511614Y78150D03*
X1497441D03*
X1490354Y120276D03*
X1511614Y120670D03*
X1532874Y67914D03*
Y110433D03*
X1525787Y106496D03*
X1532874Y96260D03*
X1525787Y92323D03*
X1532874Y82087D03*
X1525787Y78150D03*
Y120670D03*
G54D28*
X255410Y607833D03*
X260910D03*
X1862652Y846508D03*
X1860276Y916059D03*
Y912059D03*
X1873099Y817150D03*
X1878099D03*
X1873099Y821650D03*
X1878099D03*
X1873099Y826150D03*
X1878099D03*
X1877512Y831377D03*
X1882512D03*
X1865202Y831559D03*
X1873012Y831377D03*
X1878099Y812650D03*
X1873099D03*
X1878099Y808150D03*
X1873099D03*
X1878099Y803650D03*
X1873099D03*
X1878373Y846472D03*
X1883373D03*
X1867652Y846508D03*
X1872276Y916059D03*
X1876276D03*
Y920059D03*
X1872276D03*
X1868276Y916059D03*
X1864276Y912059D03*
X1868276D03*
X1864276Y916059D03*
X1876276Y912059D03*
X1872276D03*
X1875801Y946796D03*
X1875769Y951122D03*
X1880122Y954062D03*
X1880383Y950341D03*
G36*
G01X149668Y380135D02*
G02X112735I-18466J-14781D01*
G03X119308Y392599I-29176J23351D01*
G02X143095I11894J-3623D01*
G03X149668Y380135I35749J10887D01*
G37*
G36*
G01X149667Y832891D02*
G02X112734I-18466J-14781D01*
G03X119307Y845355I-29176J23351D01*
G02X143094I11894J-3623D01*
G03X149667Y832891I35749J10887D01*
G37*
G36*
G01X149668Y1285647D02*
G02X112735I-18466J-14781D01*
G03X119308Y1298111I-29176J23351D01*
G02X143095I11894J-3623D01*
G03X149668Y1285647I35749J10887D01*
G37*
G36*
G01X397699Y380135D02*
G02X360766I-18467J-14781D01*
G03X367339Y392599I-29176J23351D01*
G02X391126I11894J-3623D01*
G03X397699Y380135I35749J10887D01*
G37*
G36*
G01Y832891D02*
G02X360766I-18467J-14781D01*
G03X367339Y845355I-29176J23351D01*
G02X391126I11894J-3623D01*
G03X397699Y832891I35749J10887D01*
G37*
G36*
G01Y1285647D02*
G02X360766I-18467J-14781D01*
G03X367339Y1298111I-29176J23351D01*
G02X391126I11894J-3623D01*
G03X397699Y1285647I35749J10887D01*
G37*
G36*
G01X645730Y380135D02*
G02X608797I-18466J-14781D01*
G03X615370Y392599I-29176J23351D01*
G02X639157I11893J-3623D01*
G03X645730Y380135I35749J10887D01*
G37*
G36*
G01Y832891D02*
G02X608797I-18466J-14781D01*
G03X615370Y845355I-29176J23351D01*
G02X639157I11893J-3623D01*
G03X645730Y832891I35749J10887D01*
G37*
G36*
G01Y1285647D02*
G02X608797I-18466J-14781D01*
G03X615370Y1298111I-29176J23351D01*
G02X639157I11893J-3623D01*
G03X645730Y1285647I35749J10887D01*
G37*
G36*
G01X814924Y265984D02*
G02X777991I-18467J-14781D01*
G03X784564Y278448I-29176J23351D01*
G02X808351I11893J-3623D01*
G03X814924Y265984I35749J10887D01*
G37*
G36*
G01Y738425D02*
G02X777991I-18467J-14781D01*
G03X784564Y750889I-29176J23351D01*
G02X808351I11893J-3623D01*
G03X814924Y738425I35749J10887D01*
G37*
G36*
G01X979885Y1090394D02*
G02X942952I-18467J-14781D01*
G03X949525Y1102858I-29176J23351D01*
G02X973312I11894J-3623D01*
G03X979885Y1090394I35749J10887D01*
G37*
G36*
G01Y1432913D02*
G02X942952I-18467J-14781D01*
G03X949525Y1445377I-29176J23351D01*
G02X973312I11894J-3623D01*
G03X979885Y1432913I35749J10887D01*
G37*
G36*
G01X1200357Y558898D02*
G02X1163424I-18467J-14781D01*
G03X1169997Y571362I-29176J23351D01*
G02X1193784I11894J-3623D01*
G03X1200357Y558898I35749J10887D01*
G37*
G36*
G01X1200337Y972261D02*
G02X1163404I-18467J-14781D01*
G03X1169977Y984725I-29176J23351D01*
G02X1193764I11894J-3623D01*
G03X1200337Y972261I35749J10887D01*
G37*
G36*
G01X1200357Y1562835D02*
G02X1163424I-18467J-14781D01*
G03X1169997Y1575299I-29176J23351D01*
G02X1193784I11894J-3623D01*
G03X1200357Y1562835I35749J10887D01*
G37*
G36*
G01X1320337Y380135D02*
G02X1283404I-18467J-14781D01*
G03X1289977Y392599I-29176J23351D01*
G02X1313764I11894J-3623D01*
G03X1320337Y380135I35749J10887D01*
G37*
G36*
G01Y832891D02*
G02X1283404I-18467J-14781D01*
G03X1289977Y845355I-29176J23351D01*
G02X1313764I11894J-3623D01*
G03X1320337Y832891I35749J10887D01*
G37*
G36*
G01Y1285647D02*
G02X1283404I-18467J-14781D01*
G03X1289977Y1298111I-29176J23351D01*
G02X1313764I11894J-3623D01*
G03X1320337Y1285647I35749J10887D01*
G37*
G36*
G01X1568368Y380135D02*
G02X1531435I-18467J-14781D01*
G03X1538008Y392599I-29176J23351D01*
G02X1561795I11894J-3623D01*
G03X1568368Y380135I35749J10887D01*
G37*
G36*
G01Y832891D02*
G02X1531435I-18467J-14781D01*
G03X1538008Y845355I-29176J23351D01*
G02X1561795I11894J-3623D01*
G03X1568368Y832891I35749J10887D01*
G37*
G36*
G01Y1285647D02*
G02X1531435I-18467J-14781D01*
G03X1538008Y1298111I-29176J23351D01*
G02X1561795I11894J-3623D01*
G03X1568368Y1285647I35749J10887D01*
G37*
G36*
G01X1816400Y380135D02*
G02X1779467I-18466J-14781D01*
G03X1786040Y392599I-29176J23351D01*
G02X1809827I11894J-3623D01*
G03X1816400Y380135I35749J10887D01*
G37*
G36*
G01Y832891D02*
G02X1779467I-18466J-14781D01*
G03X1786040Y845355I-29176J23351D01*
G02X1809827I11894J-3623D01*
G03X1816400Y832891I35749J10887D01*
G37*
G36*
G01Y1285647D02*
G02X1779467I-18466J-14781D01*
G03X1786040Y1298111I-29176J23351D01*
G02X1809827I11894J-3623D01*
G03X1816400Y1285647I35749J10887D01*
G37*
%LPC*%
G75*
G54D46*
G01X363248Y-425196D02*
Y-505196D01*
G01D02*
X1639148D01*
G01X359248Y-409196D02*
G02I-12000J0D01*
G01X354098D02*
G02I-6850J0D01*
G01X347248Y-425196D02*
Y-393196D01*
G01X363248Y-425196D02*
X1639148D01*
G01X363248Y-460696D02*
X1639148D01*
G01X363248Y-409196D02*
X331248D01*
G01X720748Y-425196D02*
Y-505196D01*
G01X858248Y-425196D02*
Y-505196D01*
G01X973248Y-425196D02*
Y-505196D01*
G01X1271648Y-425196D02*
Y-505196D01*
G01X1441648Y-425196D02*
Y-505196D01*
G01X1639148Y-425196D02*
Y-505196D01*
G01X1667148Y-409196D02*
G02I-12000J0D01*
G01X1661998D02*
G02I-6850J0D01*
G01X1655148Y-425196D02*
Y-393196D01*
G01X1671148Y-409196D02*
X1639148D01*
G54D47*
G01X394744Y-485863D02*
X395618Y-484988D01*
X396273Y-483530D01*
X396710Y-481487D01*
X396273Y-479738D01*
X395400Y-478571D01*
X393871Y-477696D01*
X387976D01*
Y-495196D01*
X395181D01*
X396710Y-494030D01*
X397583Y-492279D01*
X398020Y-490238D01*
X397583Y-488196D01*
X396273Y-486446D01*
X394744Y-485863D01*
X387976D01*
G01X407441Y-495196D02*
Y-483530D01*
G01Y-485863D02*
X408533Y-484696D01*
X409625Y-483821D01*
X411153Y-483530D01*
X412244Y-483821D01*
X413555Y-484696D01*
G01X423413Y-500446D02*
X424723Y-501029D01*
X426470Y-500446D01*
X427561Y-499280D01*
X428435Y-497821D01*
X429744Y-493155D01*
X432583Y-483530D01*
G01X425596D02*
X429744Y-493155D01*
G01X448991Y-484988D02*
X447463Y-483821D01*
X446153Y-483530D01*
X444406Y-484113D01*
X443096Y-485279D01*
X442223Y-487321D01*
X442004Y-489363D01*
X442223Y-491405D01*
X443096Y-493155D01*
X444406Y-494613D01*
X446153Y-495196D01*
X447681Y-494613D01*
X448991Y-493446D01*
G01X459723Y-487321D02*
X466710D01*
X466055Y-485279D01*
X464963Y-484113D01*
X463435Y-483530D01*
X461906Y-483821D01*
X460596Y-484696D01*
X459723Y-486738D01*
X459286Y-488488D01*
Y-490238D01*
X459723Y-491988D01*
X460815Y-493738D01*
X462125Y-494904D01*
X463653Y-495196D01*
X465181Y-494613D01*
X466710Y-492863D01*
G01X502801Y-479155D02*
X501491Y-478279D01*
X499963Y-477696D01*
X498216D01*
X496251Y-478571D01*
X494723Y-480029D01*
X493631Y-481780D01*
X492758Y-484696D01*
X492539Y-487321D01*
X492976Y-489946D01*
X493631Y-491696D01*
X494941Y-493446D01*
X496470Y-494613D01*
X497998Y-495196D01*
X499526D01*
X501055Y-494613D01*
X502365Y-493738D01*
X503457Y-492572D01*
G01X519428Y-495196D02*
Y-483530D01*
G01Y-485571D02*
X518555Y-484405D01*
X517244Y-483821D01*
X515716Y-483530D01*
X514188Y-484113D01*
X512878Y-485279D01*
X512004Y-487029D01*
X511568Y-489363D01*
X512004Y-491696D01*
X512878Y-493446D01*
X514188Y-494613D01*
X515716Y-495196D01*
X517244Y-494904D01*
X518555Y-494030D01*
X519428Y-492863D01*
G01X529286Y-495196D02*
Y-483530D01*
G01Y-486446D02*
X530160Y-484988D01*
X531470Y-483821D01*
X533216Y-483530D01*
X534744Y-483821D01*
X536055Y-484988D01*
X536710Y-487029D01*
Y-495196D01*
G01X545913Y-500446D02*
X547223Y-501029D01*
X548970Y-500446D01*
X550061Y-499280D01*
X550935Y-497821D01*
X552244Y-493155D01*
X555083Y-483530D01*
G01X548096D02*
X552244Y-493155D01*
G01X567998Y-495196D02*
X566688Y-494904D01*
X565378Y-493738D01*
X564504Y-491696D01*
X564068Y-489363D01*
X564504Y-487029D01*
X565378Y-484988D01*
X566688Y-483821D01*
X567998Y-483530D01*
X569308Y-483821D01*
X570618Y-484988D01*
X571491Y-487029D01*
X571710Y-489363D01*
X571491Y-491696D01*
X570618Y-493738D01*
X569308Y-494904D01*
X567998Y-495196D01*
G01X581786D02*
Y-483530D01*
G01Y-486446D02*
X582660Y-484988D01*
X583970Y-483821D01*
X585716Y-483530D01*
X587244Y-483821D01*
X588555Y-484988D01*
X589210Y-487029D01*
Y-495196D01*
G01X616350D02*
Y-477696D01*
X624646D01*
G01X621590Y-486154D02*
X616350D01*
G01X637998Y-495779D02*
X637561Y-495488D01*
Y-494904D01*
X637998Y-494613D01*
X638435Y-494904D01*
Y-495488D01*
X637998Y-495779D01*
G01X650695Y-495196D02*
Y-477696D01*
X655061D01*
X656808Y-478571D01*
X658118Y-479738D01*
X659210Y-481487D01*
X660083Y-483530D01*
X660301Y-486446D01*
X660083Y-489363D01*
X659210Y-491405D01*
X658118Y-493155D01*
X656808Y-494321D01*
X655061Y-495196D01*
X650695D01*
G01X668631D02*
Y-477696D01*
X673871D01*
X675618Y-478571D01*
X676928Y-480613D01*
X677365Y-482946D01*
X676928Y-485279D01*
X675836Y-487029D01*
X673871Y-487905D01*
X668631D01*
G01X692244Y-485863D02*
X693118Y-484988D01*
X693773Y-483530D01*
X694210Y-481487D01*
X693773Y-479738D01*
X692900Y-478571D01*
X691371Y-477696D01*
X685476D01*
Y-495196D01*
X692681D01*
X694210Y-494030D01*
X695083Y-492279D01*
X695520Y-490238D01*
X695083Y-488196D01*
X693773Y-486446D01*
X692244Y-485863D01*
X685476D01*
G01X501071Y-450196D02*
Y-432696D01*
X506748Y-447279D01*
X512425Y-432696D01*
Y-450196D01*
G01X524248D02*
X522938Y-449904D01*
X521628Y-448738D01*
X520754Y-446696D01*
X520318Y-444363D01*
X520754Y-442029D01*
X521628Y-439988D01*
X522938Y-438821D01*
X524248Y-438530D01*
X525558Y-438821D01*
X526868Y-439988D01*
X527741Y-442029D01*
X527960Y-444363D01*
X527741Y-446696D01*
X526868Y-448738D01*
X525558Y-449904D01*
X524248Y-450196D01*
G01X545678Y-432696D02*
Y-450196D01*
G01Y-447572D02*
X544805Y-449030D01*
X543494Y-449904D01*
X541966Y-450196D01*
X540220Y-449613D01*
X538910Y-448155D01*
X538036Y-446405D01*
X537818Y-444363D01*
X538036Y-442321D01*
X538910Y-440571D01*
X540220Y-439113D01*
X541966Y-438530D01*
X543494Y-438821D01*
X544586Y-439405D01*
X545678Y-440571D01*
G01X555973Y-442321D02*
X562960D01*
X562305Y-440279D01*
X561213Y-439113D01*
X559685Y-438530D01*
X558156Y-438821D01*
X556846Y-439696D01*
X555973Y-441738D01*
X555536Y-443488D01*
Y-445238D01*
X555973Y-446988D01*
X557065Y-448738D01*
X558375Y-449904D01*
X559903Y-450196D01*
X561431Y-449613D01*
X562960Y-447863D01*
G01X576748Y-450196D02*
Y-432696D01*
G01X754448Y-495196D02*
Y-477696D01*
X751828Y-481196D01*
G01Y-495196D02*
X757068D01*
G01X767800Y-487905D02*
X769328Y-485863D01*
X770638Y-484696D01*
X772385Y-484113D01*
X773913Y-484696D01*
X775005Y-485863D01*
X775878Y-487613D01*
X776096Y-489654D01*
X775878Y-491405D01*
X775005Y-493155D01*
X773694Y-494613D01*
X772166Y-495196D01*
X770420Y-494613D01*
X768891Y-492863D01*
X768018Y-490238D01*
X767800Y-487321D01*
X768236Y-483530D01*
X768891Y-481487D01*
X769983Y-479446D01*
X771511Y-477988D01*
X773040Y-477696D01*
X774568Y-478279D01*
X775660Y-479738D01*
G01X784645Y-491696D02*
X785954Y-493738D01*
X787701Y-494904D01*
X789666Y-495196D01*
X791413Y-494904D01*
X793160Y-493446D01*
X794251Y-491696D01*
X794470Y-489946D01*
X794033Y-487905D01*
X792505Y-486446D01*
X790976Y-485863D01*
X789011D01*
G01X790976D02*
X792286Y-484988D01*
X793378Y-483530D01*
X793815Y-481780D01*
X793378Y-480029D01*
X792286Y-478571D01*
X790321Y-477696D01*
X788356Y-477988D01*
X786391Y-479155D01*
G01X806948Y-495196D02*
Y-477696D01*
X804328Y-481196D01*
G01Y-495196D02*
X809568D01*
G01X819645Y-492572D02*
X820954Y-494030D01*
X822483Y-494904D01*
X824448Y-495196D01*
X826413Y-494613D01*
X827941Y-493446D01*
X829033Y-491405D01*
X829251Y-489071D01*
X828815Y-486738D01*
X827723Y-485279D01*
X826194Y-484113D01*
X824666Y-483821D01*
X823138Y-484113D01*
X821173Y-485279D01*
X821828Y-477696D01*
X827723D01*
G01X741331Y-450196D02*
Y-432696D01*
X746571D01*
X748318Y-433571D01*
X749628Y-435613D01*
X750065Y-437946D01*
X749628Y-440279D01*
X748536Y-442029D01*
X746571Y-442905D01*
X741331D01*
G01X768001Y-434155D02*
X766691Y-433279D01*
X765163Y-432696D01*
X763416D01*
X761451Y-433571D01*
X759923Y-435029D01*
X758831Y-436780D01*
X757958Y-439696D01*
X757739Y-442321D01*
X758176Y-444946D01*
X758831Y-446696D01*
X760141Y-448446D01*
X761670Y-449613D01*
X763198Y-450196D01*
X764726D01*
X766255Y-449613D01*
X767565Y-448738D01*
X768657Y-447572D01*
G01X782444Y-440863D02*
X783318Y-439988D01*
X783973Y-438530D01*
X784410Y-436487D01*
X783973Y-434738D01*
X783100Y-433571D01*
X781571Y-432696D01*
X775676D01*
Y-450196D01*
X782881D01*
X784410Y-449030D01*
X785283Y-447279D01*
X785720Y-445238D01*
X785283Y-443196D01*
X783973Y-441446D01*
X782444Y-440863D01*
X775676D01*
G01X791648Y-456029D02*
X804748D01*
G01X810676Y-450196D02*
Y-432696D01*
X820720Y-450196D01*
Y-432696D01*
G01X833198Y-450196D02*
X831451Y-449904D01*
X829923Y-448738D01*
X828613Y-446988D01*
X827739Y-444946D01*
X827303Y-442613D01*
Y-440279D01*
X827739Y-437946D01*
X828613Y-435904D01*
X829923Y-434155D01*
X831451Y-432988D01*
X833198Y-432696D01*
X834944Y-432988D01*
X836473Y-434155D01*
X837783Y-435904D01*
X838657Y-437946D01*
X839093Y-440279D01*
Y-442613D01*
X838657Y-444946D01*
X837783Y-446988D01*
X836473Y-448738D01*
X834944Y-449904D01*
X833198Y-450196D01*
G01X884039Y-432696D02*
X889498Y-450196D01*
X894957Y-432696D01*
G01X911365Y-450196D02*
X902631D01*
Y-432696D01*
X911365D01*
G01X907871Y-441154D02*
X902631D01*
G01X920131Y-450196D02*
Y-432696D01*
X925590D01*
X927336Y-433571D01*
X928428Y-434738D01*
X928865Y-437071D01*
X928428Y-439405D01*
X927118Y-440863D01*
X925590Y-441738D01*
X920131D01*
G01X925590D02*
X928865Y-450196D01*
G01X941998Y-450779D02*
X941561Y-450488D01*
Y-449904D01*
X941998Y-449613D01*
X942435Y-449904D01*
Y-450488D01*
X941998Y-450779D01*
G01X915748Y-495196D02*
Y-477696D01*
X913128Y-481196D01*
G01Y-495196D02*
X918368D01*
G01X1161715Y-477696D02*
Y-495196D01*
X1152981D01*
G01X1140285D02*
X1139848Y-491405D01*
X1139193Y-488196D01*
X1138320Y-485279D01*
X1137228Y-482071D01*
X1135481Y-477696D01*
X1144215D01*
G01X1127807D02*
X1122348Y-495196D01*
X1116889Y-477696D01*
G01X1100045Y-479155D02*
X1101355Y-478279D01*
X1102883Y-477696D01*
X1104630D01*
X1106595Y-478571D01*
X1108123Y-480029D01*
X1109215Y-481780D01*
X1110088Y-484696D01*
X1110307Y-487321D01*
X1109870Y-489946D01*
X1109215Y-491696D01*
X1107905Y-493446D01*
X1106376Y-494613D01*
X1104848Y-495196D01*
X1103320D01*
X1101791Y-494613D01*
X1100481Y-493738D01*
X1099389Y-492572D01*
G01X1082545Y-479155D02*
X1083855Y-478279D01*
X1085383Y-477696D01*
X1087130D01*
X1089095Y-478571D01*
X1090623Y-480029D01*
X1091715Y-481780D01*
X1092588Y-484696D01*
X1092807Y-487321D01*
X1092370Y-489946D01*
X1091715Y-491696D01*
X1090405Y-493446D01*
X1088876Y-494613D01*
X1087348Y-495196D01*
X1085820D01*
X1084291Y-494613D01*
X1082981Y-493738D01*
X1081889Y-492572D01*
G01X1082981Y-432696D02*
Y-450196D01*
X1091715D01*
G01X1108778D02*
Y-438530D01*
G01Y-440571D02*
X1107905Y-439405D01*
X1106594Y-438821D01*
X1105066Y-438530D01*
X1103538Y-439113D01*
X1102228Y-440279D01*
X1101354Y-442029D01*
X1100918Y-444363D01*
X1101354Y-446696D01*
X1102228Y-448446D01*
X1103538Y-449613D01*
X1105066Y-450196D01*
X1106594Y-449904D01*
X1107905Y-449030D01*
X1108778Y-447863D01*
G01X1117763Y-455446D02*
X1119073Y-456029D01*
X1120820Y-455446D01*
X1121911Y-454280D01*
X1122785Y-452821D01*
X1124094Y-448155D01*
X1126933Y-438530D01*
G01X1119946D02*
X1124094Y-448155D01*
G01X1136573Y-442321D02*
X1143560D01*
X1142905Y-440279D01*
X1141813Y-439113D01*
X1140285Y-438530D01*
X1138756Y-438821D01*
X1137446Y-439696D01*
X1136573Y-441738D01*
X1136136Y-443488D01*
Y-445238D01*
X1136573Y-446988D01*
X1137665Y-448738D01*
X1138975Y-449904D01*
X1140503Y-450196D01*
X1142031Y-449613D01*
X1143560Y-447863D01*
G01X1154291Y-450196D02*
Y-438530D01*
G01Y-440863D02*
X1155383Y-439696D01*
X1156475Y-438821D01*
X1158003Y-438530D01*
X1159094Y-438821D01*
X1160405Y-439696D01*
G01X1312898Y-495196D02*
X1311151Y-494904D01*
X1309623Y-493738D01*
X1308313Y-491988D01*
X1307439Y-489946D01*
X1307003Y-487613D01*
Y-485279D01*
X1307439Y-482946D01*
X1308313Y-480904D01*
X1309623Y-479155D01*
X1311151Y-477988D01*
X1312898Y-477696D01*
X1314644Y-477988D01*
X1316173Y-479155D01*
X1317483Y-480904D01*
X1318357Y-482946D01*
X1318793Y-485279D01*
Y-487613D01*
X1318357Y-489946D01*
X1317483Y-491988D01*
X1316173Y-493738D01*
X1314644Y-494904D01*
X1312898Y-495196D01*
G01X1314644Y-490529D02*
X1317265Y-495196D01*
G01X1325595Y-477696D02*
Y-490238D01*
X1326468Y-492863D01*
X1328215Y-494613D01*
X1330398Y-495196D01*
X1332581Y-494613D01*
X1334328Y-492863D01*
X1335201Y-490238D01*
Y-477696D01*
G01X1345278D02*
X1350518D01*
G01X1347898D02*
Y-495196D01*
G01X1345278D02*
X1350518D01*
G01X1360376D02*
Y-477696D01*
X1370420Y-495196D01*
Y-477696D01*
G01X1387701Y-479155D02*
X1386391Y-478279D01*
X1384863Y-477696D01*
X1383116D01*
X1381151Y-478571D01*
X1379623Y-480029D01*
X1378531Y-481780D01*
X1377658Y-484696D01*
X1377439Y-487321D01*
X1377876Y-489946D01*
X1378531Y-491696D01*
X1379841Y-493446D01*
X1381370Y-494613D01*
X1382898Y-495196D01*
X1384426D01*
X1385955Y-494613D01*
X1387265Y-493738D01*
X1388357Y-492572D01*
G01X1400398Y-495196D02*
Y-487321D01*
X1396031Y-477696D01*
G01X1404765D02*
X1400398Y-487321D01*
G01X1290595Y-450196D02*
Y-432696D01*
X1294961D01*
X1296708Y-433571D01*
X1298018Y-434738D01*
X1299110Y-436487D01*
X1299983Y-438530D01*
X1300201Y-441446D01*
X1299983Y-444363D01*
X1299110Y-446405D01*
X1298018Y-448155D01*
X1296708Y-449321D01*
X1294961Y-450196D01*
X1290595D01*
G01X1309623Y-442321D02*
X1316610D01*
X1315955Y-440279D01*
X1314863Y-439113D01*
X1313335Y-438530D01*
X1311806Y-438821D01*
X1310496Y-439696D01*
X1309623Y-441738D01*
X1309186Y-443488D01*
Y-445238D01*
X1309623Y-446988D01*
X1310715Y-448738D01*
X1312025Y-449904D01*
X1313553Y-450196D01*
X1315081Y-449613D01*
X1316610Y-447863D01*
G01X1327123Y-448155D02*
X1328215Y-449321D01*
X1329743Y-450196D01*
X1331053D01*
X1332363Y-449613D01*
X1333236Y-448738D01*
X1333673Y-447572D01*
X1333455Y-445821D01*
X1332581Y-444946D01*
X1328651Y-443196D01*
X1327778Y-441154D01*
X1328215Y-439696D01*
X1329088Y-438821D01*
X1330398Y-438530D01*
X1331708Y-438821D01*
X1333018Y-439696D01*
G01X1347898Y-438530D02*
Y-450196D01*
G01Y-433863D02*
X1347461Y-433571D01*
Y-432988D01*
X1347898Y-432696D01*
X1348335Y-432988D01*
Y-433571D01*
X1347898Y-433863D01*
G01X1362341Y-454571D02*
X1363870Y-455738D01*
X1365616Y-456029D01*
X1367144Y-455738D01*
X1368455Y-454280D01*
X1369328Y-452238D01*
Y-438530D01*
G01Y-440863D02*
X1368455Y-439696D01*
X1367144Y-438821D01*
X1365616Y-438530D01*
X1363870Y-439113D01*
X1362778Y-440279D01*
X1361904Y-442321D01*
X1361468Y-444363D01*
X1361686Y-446113D01*
X1362560Y-448155D01*
X1363870Y-449613D01*
X1365616Y-450196D01*
X1366926Y-449904D01*
X1368455Y-448738D01*
X1369328Y-447572D01*
G01X1379186Y-450196D02*
Y-438530D01*
G01Y-441446D02*
X1380060Y-439988D01*
X1381370Y-438821D01*
X1383116Y-438530D01*
X1384644Y-438821D01*
X1385955Y-439988D01*
X1386610Y-442029D01*
Y-450196D01*
G01X1397123Y-442321D02*
X1404110D01*
X1403455Y-440279D01*
X1402363Y-439113D01*
X1400835Y-438530D01*
X1399306Y-438821D01*
X1397996Y-439696D01*
X1397123Y-441738D01*
X1396686Y-443488D01*
Y-445238D01*
X1397123Y-446988D01*
X1398215Y-448738D01*
X1399525Y-449904D01*
X1401053Y-450196D01*
X1402581Y-449613D01*
X1404110Y-447863D01*
G01X1414841Y-450196D02*
Y-438530D01*
G01Y-440863D02*
X1415933Y-439696D01*
X1417025Y-438821D01*
X1418553Y-438530D01*
X1419644Y-438821D01*
X1420955Y-439696D01*
G01X1461598Y-477696D02*
X1459851Y-478279D01*
X1458541Y-479738D01*
X1457668Y-481487D01*
X1457013Y-483821D01*
X1456795Y-486446D01*
X1457013Y-489071D01*
X1457668Y-491405D01*
X1458541Y-493155D01*
X1459851Y-494613D01*
X1461598Y-495196D01*
X1463344Y-494613D01*
X1464655Y-493155D01*
X1465528Y-491405D01*
X1466183Y-489071D01*
X1466401Y-486446D01*
X1466183Y-483821D01*
X1465528Y-481487D01*
X1464655Y-479738D01*
X1463344Y-478279D01*
X1461598Y-477696D01*
G01X1474950Y-487905D02*
X1476478Y-485863D01*
X1477788Y-484696D01*
X1479535Y-484113D01*
X1481063Y-484696D01*
X1482155Y-485863D01*
X1483028Y-487613D01*
X1483246Y-489654D01*
X1483028Y-491405D01*
X1482155Y-493155D01*
X1480844Y-494613D01*
X1479316Y-495196D01*
X1477570Y-494613D01*
X1476041Y-492863D01*
X1475168Y-490238D01*
X1474950Y-487321D01*
X1475386Y-483530D01*
X1476041Y-481487D01*
X1477133Y-479446D01*
X1478661Y-477988D01*
X1480190Y-477696D01*
X1481718Y-478279D01*
X1482810Y-479738D01*
G01X1492668Y-495779D02*
X1500528Y-477696D01*
G01X1514098D02*
X1512351Y-478279D01*
X1511041Y-479738D01*
X1510168Y-481487D01*
X1509513Y-483821D01*
X1509295Y-486446D01*
X1509513Y-489071D01*
X1510168Y-491405D01*
X1511041Y-493155D01*
X1512351Y-494613D01*
X1514098Y-495196D01*
X1515844Y-494613D01*
X1517155Y-493155D01*
X1518028Y-491405D01*
X1518683Y-489071D01*
X1518901Y-486446D01*
X1518683Y-483821D01*
X1518028Y-481487D01*
X1517155Y-479738D01*
X1515844Y-478279D01*
X1514098Y-477696D01*
G01X1527886Y-493155D02*
X1529415Y-494613D01*
X1531161Y-495196D01*
X1532908Y-494613D01*
X1534436Y-492863D01*
X1535528Y-490238D01*
X1535965Y-487613D01*
Y-484405D01*
X1535528Y-481780D01*
X1534436Y-479446D01*
X1533126Y-478279D01*
X1531598Y-477696D01*
X1529851Y-478279D01*
X1528541Y-479446D01*
X1527668Y-481196D01*
X1527231Y-483530D01*
X1527668Y-485571D01*
X1528760Y-487613D01*
X1530070Y-488780D01*
X1531598Y-489071D01*
X1533344Y-488488D01*
X1534655Y-487029D01*
X1535965Y-484405D01*
G01X1545168Y-495779D02*
X1553028Y-477696D01*
G01X1562450Y-480613D02*
X1563760Y-478863D01*
X1565288Y-477988D01*
X1567035Y-477696D01*
X1569218Y-478279D01*
X1570746Y-479738D01*
X1571183Y-481487D01*
X1570965Y-483238D01*
X1570091Y-484696D01*
X1565725Y-487613D01*
X1563760Y-489654D01*
X1562450Y-492572D01*
X1562013Y-495196D01*
X1571183D01*
G01X1584098Y-477696D02*
X1582351Y-478279D01*
X1581041Y-479738D01*
X1580168Y-481487D01*
X1579513Y-483821D01*
X1579295Y-486446D01*
X1579513Y-489071D01*
X1580168Y-491405D01*
X1581041Y-493155D01*
X1582351Y-494613D01*
X1584098Y-495196D01*
X1585844Y-494613D01*
X1587155Y-493155D01*
X1588028Y-491405D01*
X1588683Y-489071D01*
X1588901Y-486446D01*
X1588683Y-483821D01*
X1588028Y-481487D01*
X1587155Y-479738D01*
X1585844Y-478279D01*
X1584098Y-477696D01*
G01X1601598Y-495196D02*
Y-477696D01*
X1598978Y-481196D01*
G01Y-495196D02*
X1604218D01*
G01X1618661D02*
X1619098Y-491405D01*
X1619753Y-488196D01*
X1620626Y-485279D01*
X1621718Y-482071D01*
X1623465Y-477696D01*
X1614731D01*
G01X1509295Y-450196D02*
Y-432696D01*
X1513661D01*
X1515408Y-433571D01*
X1516718Y-434738D01*
X1517810Y-436487D01*
X1518683Y-438530D01*
X1518901Y-441446D01*
X1518683Y-444363D01*
X1517810Y-446405D01*
X1516718Y-448155D01*
X1515408Y-449321D01*
X1513661Y-450196D01*
X1509295D01*
G01X1535528D02*
Y-438530D01*
G01Y-440571D02*
X1534655Y-439405D01*
X1533344Y-438821D01*
X1531816Y-438530D01*
X1530288Y-439113D01*
X1528978Y-440279D01*
X1528104Y-442029D01*
X1527668Y-444363D01*
X1528104Y-446696D01*
X1528978Y-448446D01*
X1530288Y-449613D01*
X1531816Y-450196D01*
X1533344Y-449904D01*
X1534655Y-449030D01*
X1535528Y-447863D01*
G01X1549098Y-432696D02*
Y-450196D01*
G01X1546041Y-438530D02*
X1552155D01*
G01X1563323Y-442321D02*
X1570310D01*
X1569655Y-440279D01*
X1568563Y-439113D01*
X1567035Y-438530D01*
X1565506Y-438821D01*
X1564196Y-439696D01*
X1563323Y-441738D01*
X1562886Y-443488D01*
Y-445238D01*
X1563323Y-446988D01*
X1564415Y-448738D01*
X1565725Y-449904D01*
X1567253Y-450196D01*
X1568781Y-449613D01*
X1570310Y-447863D01*
M02*
